FILE_TYPE = MACRO_DRAWING;
SET COLOR_WIRE YELLOW;
SET COLOR_PROP ORANGE;
SET COLOR_DOT WHITE;
SET COLOR_ARC YELLOW;
SET COLOR_BODY GREEN;
SET COLOR_NOTE PURPLE;
SET PROP_DISPLAY VALUE;
SET PAGE_NUMBER P85;
FORCEADD GND..1
(-650 1750);
FORCEPROP 3 LASTPIN (-650 1800) SIG_NAME GND\g
J 0
(-640 1810);
DISPLAY 0.659574 (-640 1810);
PAINT MONO (-640 1810);
DISPLAY INVISIBLE (-640 1810);
FORCEPROP 1 LAST VOLTAGE 0.0
J 0
(-695 1707);
DISPLAY 0.723404 (-695 1707);
PAINT SKYBLUE (-695 1707);
DISPLAY INVISIBLE (-695 1707);
FORCEPROP 2 LAST CDS_LIB mstr_symbols
J 0
(-650 1750);
DISPLAY 0.723404 (-650 1750);
DISPLAY INVISIBLE (-650 1750);
FORCEPROP 1 LAST SIZE 1B
J 0
(-575 1700);
DISPLAY 0.851064 (-575 1700);
PAINT GREEN (-575 1700);
DISPLAY INVISIBLE (-575 1700);
FORCEPROP 1 LAST BODY_TYPE PLUMBING
J 0
(-695 1707);
DISPLAY 0.340426 (-695 1707);
PAINT GREEN (-695 1707);
DISPLAY INVISIBLE (-695 1707);
FORCEPROP 1 LAST HDL_POWER GND
J 0
(-650 1900);
DISPLAY 0.851064 (-650 1900);
PAINT GREEN (-650 1900);
DISPLAY INVISIBLE (-650 1900);
FORCEPROP 1 LAST PATH I115
J 0
(-575 1750);
DISPLAY 0.872340 (-575 1750);
PAINT GREEN (-575 1750);
DISPLAY INVISIBLE (-575 1750);
FORCEADD GND..1
(-2250 1950);
FORCEPROP 3 LASTPIN (-2250 2000) SIG_NAME GND\g
J 0
(-2240 2010);
DISPLAY 0.659574 (-2240 2010);
PAINT MONO (-2240 2010);
DISPLAY INVISIBLE (-2240 2010);
FORCEPROP 1 LAST VOLTAGE 0.0
J 0
(-2295 1907);
DISPLAY 0.723404 (-2295 1907);
PAINT SKYBLUE (-2295 1907);
DISPLAY INVISIBLE (-2295 1907);
FORCEPROP 2 LAST CDS_LIB mstr_symbols
J 0
(-2250 1950);
DISPLAY 0.723404 (-2250 1950);
DISPLAY INVISIBLE (-2250 1950);
FORCEPROP 1 LAST SIZE 1B
J 0
(-2175 1900);
DISPLAY 0.851064 (-2175 1900);
PAINT GREEN (-2175 1900);
DISPLAY INVISIBLE (-2175 1900);
FORCEPROP 1 LAST BODY_TYPE PLUMBING
J 0
(-2295 1907);
DISPLAY 0.340426 (-2295 1907);
PAINT GREEN (-2295 1907);
DISPLAY INVISIBLE (-2295 1907);
FORCEPROP 1 LAST HDL_POWER GND
J 0
(-2250 2100);
DISPLAY 0.851064 (-2250 2100);
PAINT GREEN (-2250 2100);
DISPLAY INVISIBLE (-2250 2100);
FORCEPROP 1 LAST PATH I116
J 0
(-2175 1950);
DISPLAY 0.872340 (-2175 1950);
PAINT GREEN (-2175 1950);
DISPLAY INVISIBLE (-2175 1950);
FORCEADD TAP..1
R 2
(-7750 4025);
FORCEPROP 3 LASTPIN (-7700 4025) SIG_NAME M_A_CPU0_SA_CB<7>
J 0
(-7690 4035);
DISPLAY 0.659574 (-7690 4035);
PAINT MONO (-7690 4035);
DISPLAY INVISIBLE (-7690 4035);
FORCEPROP 1 LASTPIN (-7700 4025) BN 7
J 2
(-7688 4033);
DISPLAY 0.489362 (-7688 4033);
PAINT GREEN (-7688 4033);
FORCEPROP 2 LAST CDS_LIB mstr_standard
J 0
(-7750 4025);
DISPLAY 0.723404 (-7750 4025);
PAINT MONO (-7750 4025);
DISPLAY INVISIBLE (-7750 4025);
FORCEPROP 1 LAST BODY_TYPE PLUMBING
J 2
(-7750 4075);
DISPLAY 0.872340 (-7750 4075);
PAINT GREEN (-7750 4075);
DISPLAY INVISIBLE (-7750 4075);
FORCEPROP 1 LAST HDL_TAP TRUE
J 2
(-8075 3900);
DISPLAY 0.872340 (-8075 3900);
DISPLAY INVISIBLE (-8075 3900);
FORCEPROP 1 LAST PATH I210
J 2
(-7748 4025);
DISPLAY 0.872340 (-7748 4025);
PAINT GREEN (-7748 4025);
DISPLAY INVISIBLE (-7748 4025);
FORCEADD TAP..1
R 2
(-7750 3925);
FORCEPROP 3 LASTPIN (-7700 3925) SIG_NAME M_A_CPU0_SA_CB<5>
J 0
(-7690 3935);
DISPLAY 0.659574 (-7690 3935);
PAINT MONO (-7690 3935);
DISPLAY INVISIBLE (-7690 3935);
FORCEPROP 1 LASTPIN (-7700 3925) BN 5
J 2
(-7688 3933);
DISPLAY 0.489362 (-7688 3933);
PAINT GREEN (-7688 3933);
FORCEPROP 2 LAST CDS_LIB mstr_standard
J 0
(-7750 3925);
DISPLAY 0.723404 (-7750 3925);
PAINT MONO (-7750 3925);
DISPLAY INVISIBLE (-7750 3925);
FORCEPROP 1 LAST BODY_TYPE PLUMBING
J 2
(-7750 3975);
DISPLAY 0.872340 (-7750 3975);
PAINT GREEN (-7750 3975);
DISPLAY INVISIBLE (-7750 3975);
FORCEPROP 1 LAST HDL_TAP TRUE
J 2
(-8075 3800);
DISPLAY 0.872340 (-8075 3800);
DISPLAY INVISIBLE (-8075 3800);
FORCEPROP 1 LAST PATH I211
J 2
(-7748 3925);
DISPLAY 0.872340 (-7748 3925);
PAINT GREEN (-7748 3925);
DISPLAY INVISIBLE (-7748 3925);
FORCEADD TAP..1
R 2
(-7750 3975);
FORCEPROP 3 LASTPIN (-7700 3975) SIG_NAME M_A_CPU0_SA_CB<6>
J 0
(-7690 3985);
DISPLAY 0.659574 (-7690 3985);
PAINT MONO (-7690 3985);
DISPLAY INVISIBLE (-7690 3985);
FORCEPROP 1 LASTPIN (-7700 3975) BN 6
J 2
(-7688 3983);
DISPLAY 0.489362 (-7688 3983);
PAINT GREEN (-7688 3983);
FORCEPROP 2 LAST CDS_LIB mstr_standard
J 0
(-7750 3975);
DISPLAY 0.723404 (-7750 3975);
PAINT MONO (-7750 3975);
DISPLAY INVISIBLE (-7750 3975);
FORCEPROP 1 LAST BODY_TYPE PLUMBING
J 2
(-7750 4025);
DISPLAY 0.872340 (-7750 4025);
PAINT GREEN (-7750 4025);
DISPLAY INVISIBLE (-7750 4025);
FORCEPROP 1 LAST HDL_TAP TRUE
J 2
(-8075 3850);
DISPLAY 0.872340 (-8075 3850);
DISPLAY INVISIBLE (-8075 3850);
FORCEPROP 1 LAST PATH I212
J 2
(-7748 3975);
DISPLAY 0.872340 (-7748 3975);
PAINT GREEN (-7748 3975);
DISPLAY INVISIBLE (-7748 3975);
FORCEADD TAP..1
R 2
(-7750 3825);
FORCEPROP 3 LASTPIN (-7700 3825) SIG_NAME M_A_CPU0_SA_CB<3>
J 0
(-7690 3835);
DISPLAY 0.659574 (-7690 3835);
PAINT MONO (-7690 3835);
DISPLAY INVISIBLE (-7690 3835);
FORCEPROP 1 LASTPIN (-7700 3825) BN 3
J 2
(-7688 3833);
DISPLAY 0.489362 (-7688 3833);
PAINT GREEN (-7688 3833);
FORCEPROP 2 LAST CDS_LIB mstr_standard
J 0
(-7750 3825);
DISPLAY 0.723404 (-7750 3825);
PAINT MONO (-7750 3825);
DISPLAY INVISIBLE (-7750 3825);
FORCEPROP 1 LAST BODY_TYPE PLUMBING
J 2
(-7750 3875);
DISPLAY 0.872340 (-7750 3875);
PAINT GREEN (-7750 3875);
DISPLAY INVISIBLE (-7750 3875);
FORCEPROP 1 LAST HDL_TAP TRUE
J 2
(-8075 3700);
DISPLAY 0.872340 (-8075 3700);
DISPLAY INVISIBLE (-8075 3700);
FORCEPROP 1 LAST PATH I213
J 2
(-7748 3825);
DISPLAY 0.872340 (-7748 3825);
PAINT GREEN (-7748 3825);
DISPLAY INVISIBLE (-7748 3825);
FORCEADD TAP..1
R 2
(-7750 3875);
FORCEPROP 3 LASTPIN (-7700 3875) SIG_NAME M_A_CPU0_SA_CB<4>
J 0
(-7690 3885);
DISPLAY 0.659574 (-7690 3885);
PAINT MONO (-7690 3885);
DISPLAY INVISIBLE (-7690 3885);
FORCEPROP 1 LASTPIN (-7700 3875) BN 4
J 2
(-7688 3883);
DISPLAY 0.489362 (-7688 3883);
PAINT GREEN (-7688 3883);
FORCEPROP 2 LAST CDS_LIB mstr_standard
J 0
(-7750 3875);
DISPLAY 0.723404 (-7750 3875);
PAINT MONO (-7750 3875);
DISPLAY INVISIBLE (-7750 3875);
FORCEPROP 1 LAST BODY_TYPE PLUMBING
J 2
(-7750 3925);
DISPLAY 0.872340 (-7750 3925);
PAINT GREEN (-7750 3925);
DISPLAY INVISIBLE (-7750 3925);
FORCEPROP 1 LAST HDL_TAP TRUE
J 2
(-8075 3750);
DISPLAY 0.872340 (-8075 3750);
DISPLAY INVISIBLE (-8075 3750);
FORCEPROP 1 LAST PATH I214
J 2
(-7748 3875);
DISPLAY 0.872340 (-7748 3875);
PAINT GREEN (-7748 3875);
DISPLAY INVISIBLE (-7748 3875);
FORCEADD TAP..1
R 2
(-7750 3775);
FORCEPROP 3 LASTPIN (-7700 3775) SIG_NAME M_A_CPU0_SA_CB<2>
J 0
(-7690 3785);
DISPLAY 0.659574 (-7690 3785);
PAINT MONO (-7690 3785);
DISPLAY INVISIBLE (-7690 3785);
FORCEPROP 1 LASTPIN (-7700 3775) BN 2
J 2
(-7688 3783);
DISPLAY 0.489362 (-7688 3783);
PAINT GREEN (-7688 3783);
FORCEPROP 2 LAST CDS_LIB mstr_standard
J 0
(-7750 3775);
DISPLAY 0.723404 (-7750 3775);
PAINT MONO (-7750 3775);
DISPLAY INVISIBLE (-7750 3775);
FORCEPROP 1 LAST BODY_TYPE PLUMBING
J 2
(-7750 3825);
DISPLAY 0.872340 (-7750 3825);
PAINT GREEN (-7750 3825);
DISPLAY INVISIBLE (-7750 3825);
FORCEPROP 1 LAST HDL_TAP TRUE
J 2
(-8075 3650);
DISPLAY 0.872340 (-8075 3650);
DISPLAY INVISIBLE (-8075 3650);
FORCEPROP 1 LAST PATH I215
J 2
(-7748 3775);
DISPLAY 0.872340 (-7748 3775);
PAINT GREEN (-7748 3775);
DISPLAY INVISIBLE (-7748 3775);
FORCEADD TAP..1
R 2
(-7750 3725);
FORCEPROP 3 LASTPIN (-7700 3725) SIG_NAME M_A_CPU0_SA_CB<1>
J 0
(-7690 3735);
DISPLAY 0.659574 (-7690 3735);
PAINT MONO (-7690 3735);
DISPLAY INVISIBLE (-7690 3735);
FORCEPROP 1 LASTPIN (-7700 3725) BN 1
J 2
(-7688 3733);
DISPLAY 0.489362 (-7688 3733);
PAINT GREEN (-7688 3733);
FORCEPROP 2 LAST CDS_LIB mstr_standard
J 0
(-7750 3725);
DISPLAY 0.723404 (-7750 3725);
PAINT MONO (-7750 3725);
DISPLAY INVISIBLE (-7750 3725);
FORCEPROP 1 LAST BODY_TYPE PLUMBING
J 2
(-7750 3775);
DISPLAY 0.872340 (-7750 3775);
PAINT GREEN (-7750 3775);
DISPLAY INVISIBLE (-7750 3775);
FORCEPROP 1 LAST HDL_TAP TRUE
J 2
(-8075 3600);
DISPLAY 0.872340 (-8075 3600);
DISPLAY INVISIBLE (-8075 3600);
FORCEPROP 1 LAST PATH I216
J 2
(-7748 3725);
DISPLAY 0.872340 (-7748 3725);
PAINT GREEN (-7748 3725);
DISPLAY INVISIBLE (-7748 3725);
FORCEADD TAP..1
R 2
(-7750 3675);
FORCEPROP 3 LASTPIN (-7700 3675) SIG_NAME M_A_CPU0_SA_CB<0>
J 0
(-7690 3685);
DISPLAY 0.659574 (-7690 3685);
PAINT MONO (-7690 3685);
DISPLAY INVISIBLE (-7690 3685);
FORCEPROP 1 LASTPIN (-7700 3675) BN 0
J 2
(-7688 3683);
DISPLAY 0.489362 (-7688 3683);
PAINT GREEN (-7688 3683);
FORCEPROP 2 LAST CDS_LIB mstr_standard
J 0
(-7750 3675);
DISPLAY 0.723404 (-7750 3675);
PAINT MONO (-7750 3675);
DISPLAY INVISIBLE (-7750 3675);
FORCEPROP 1 LAST BODY_TYPE PLUMBING
J 2
(-7750 3725);
DISPLAY 0.872340 (-7750 3725);
PAINT GREEN (-7750 3725);
DISPLAY INVISIBLE (-7750 3725);
FORCEPROP 1 LAST HDL_TAP TRUE
J 2
(-8075 3550);
DISPLAY 0.872340 (-8075 3550);
DISPLAY INVISIBLE (-8075 3550);
FORCEPROP 1 LAST PATH I217
J 2
(-7748 3675);
DISPLAY 0.872340 (-7748 3675);
PAINT GREEN (-7748 3675);
DISPLAY INVISIBLE (-7748 3675);
FORCEADD OFFPAGE..6
(-8350 4075);
FORCEPROP 2 LAST $XR0 10 
J 0
(-8629 4075);
DISPLAY 0.638298 (-8629 4075);
PAINT MONO (-8629 4075);
FORCEPROP 2 LAST CDS_LIB mstr_standard
J 0
(-8350 4075);
DISPLAY 0.723404 (-8350 4075);
PAINT MONO (-8350 4075);
DISPLAY INVISIBLE (-8350 4075);
FORCEPROP 1 LAST OFFPAGE TRUE
J 0
(-8025 3950);
DISPLAY 0.872340 (-8025 3950);
PAINT GREEN (-8025 3950);
DISPLAY INVISIBLE (-8025 3950);
FORCEPROP 1 LAST COMMENT_BODY TRUE
J 0
(-8250 4000);
DISPLAY 0.872340 (-8250 4000);
PAINT GREEN (-8250 4000);
DISPLAY INVISIBLE (-8250 4000);
FORCEPROP 2 LAST PATH I218
J 0
(-8600 4125);
DISPLAY 0.808511 (-8600 4125);
DISPLAY INVISIBLE (-8600 4125);
FORCEADD TAP..1
R 2
(-7750 5375);
FORCEPROP 3 LASTPIN (-7700 5375) SIG_NAME M_A_CPU0_SA_CA<5>
J 0
(-7690 5385);
DISPLAY 0.659574 (-7690 5385);
PAINT MONO (-7690 5385);
DISPLAY INVISIBLE (-7690 5385);
FORCEPROP 1 LASTPIN (-7700 5375) BN 5
J 2
(-7688 5383);
DISPLAY 0.489362 (-7688 5383);
PAINT GREEN (-7688 5383);
FORCEPROP 2 LAST CDS_LIB mstr_standard
J 0
(-7750 5375);
DISPLAY 0.723404 (-7750 5375);
PAINT MONO (-7750 5375);
DISPLAY INVISIBLE (-7750 5375);
FORCEPROP 1 LAST BODY_TYPE PLUMBING
J 2
(-7750 5425);
DISPLAY 0.872340 (-7750 5425);
PAINT GREEN (-7750 5425);
DISPLAY INVISIBLE (-7750 5425);
FORCEPROP 1 LAST HDL_TAP TRUE
J 2
(-8075 5250);
DISPLAY 0.872340 (-8075 5250);
DISPLAY INVISIBLE (-8075 5250);
FORCEPROP 1 LAST PATH I227
J 2
(-7748 5375);
DISPLAY 0.872340 (-7748 5375);
PAINT GREEN (-7748 5375);
DISPLAY INVISIBLE (-7748 5375);
FORCEADD TAP..1
R 2
(-7750 5325);
FORCEPROP 3 LASTPIN (-7700 5325) SIG_NAME M_A_CPU0_SA_CA<4>
J 0
(-7690 5335);
DISPLAY 0.659574 (-7690 5335);
PAINT MONO (-7690 5335);
DISPLAY INVISIBLE (-7690 5335);
FORCEPROP 1 LASTPIN (-7700 5325) BN 4
J 2
(-7688 5333);
DISPLAY 0.489362 (-7688 5333);
PAINT GREEN (-7688 5333);
FORCEPROP 2 LAST CDS_LIB mstr_standard
J 0
(-7750 5325);
DISPLAY 0.723404 (-7750 5325);
PAINT MONO (-7750 5325);
DISPLAY INVISIBLE (-7750 5325);
FORCEPROP 1 LAST BODY_TYPE PLUMBING
J 2
(-7750 5375);
DISPLAY 0.872340 (-7750 5375);
PAINT GREEN (-7750 5375);
DISPLAY INVISIBLE (-7750 5375);
FORCEPROP 1 LAST HDL_TAP TRUE
J 2
(-8075 5200);
DISPLAY 0.872340 (-8075 5200);
DISPLAY INVISIBLE (-8075 5200);
FORCEPROP 1 LAST PATH I228
J 2
(-7748 5325);
DISPLAY 0.872340 (-7748 5325);
PAINT GREEN (-7748 5325);
DISPLAY INVISIBLE (-7748 5325);
FORCEADD TAP..1
R 2
(-7750 5425);
FORCEPROP 3 LASTPIN (-7700 5425) SIG_NAME M_A_CPU0_SA_CA<6>
J 0
(-7690 5435);
DISPLAY 0.659574 (-7690 5435);
PAINT MONO (-7690 5435);
DISPLAY INVISIBLE (-7690 5435);
FORCEPROP 1 LASTPIN (-7700 5425) BN 6
J 2
(-7688 5433);
DISPLAY 0.489362 (-7688 5433);
PAINT GREEN (-7688 5433);
FORCEPROP 2 LAST CDS_LIB mstr_standard
J 0
(-7750 5425);
DISPLAY 0.723404 (-7750 5425);
PAINT MONO (-7750 5425);
DISPLAY INVISIBLE (-7750 5425);
FORCEPROP 1 LAST BODY_TYPE PLUMBING
J 2
(-7750 5475);
DISPLAY 0.872340 (-7750 5475);
PAINT GREEN (-7750 5475);
DISPLAY INVISIBLE (-7750 5475);
FORCEPROP 1 LAST HDL_TAP TRUE
J 2
(-8075 5300);
DISPLAY 0.872340 (-8075 5300);
DISPLAY INVISIBLE (-8075 5300);
FORCEPROP 1 LAST PATH I229
J 2
(-7748 5425);
DISPLAY 0.872340 (-7748 5425);
PAINT GREEN (-7748 5425);
DISPLAY INVISIBLE (-7748 5425);
FORCEADD TAP..1
R 2
(-7750 5275);
FORCEPROP 3 LASTPIN (-7700 5275) SIG_NAME M_A_CPU0_SA_CA<3>
J 0
(-7690 5285);
DISPLAY 0.659574 (-7690 5285);
PAINT MONO (-7690 5285);
DISPLAY INVISIBLE (-7690 5285);
FORCEPROP 1 LASTPIN (-7700 5275) BN 3
J 2
(-7688 5283);
DISPLAY 0.489362 (-7688 5283);
PAINT GREEN (-7688 5283);
FORCEPROP 2 LAST CDS_LIB mstr_standard
J 0
(-7750 5275);
DISPLAY 0.723404 (-7750 5275);
PAINT MONO (-7750 5275);
DISPLAY INVISIBLE (-7750 5275);
FORCEPROP 1 LAST BODY_TYPE PLUMBING
J 2
(-7750 5325);
DISPLAY 0.872340 (-7750 5325);
PAINT GREEN (-7750 5325);
DISPLAY INVISIBLE (-7750 5325);
FORCEPROP 1 LAST HDL_TAP TRUE
J 2
(-8075 5150);
DISPLAY 0.872340 (-8075 5150);
DISPLAY INVISIBLE (-8075 5150);
FORCEPROP 1 LAST PATH I230
J 2
(-7748 5275);
DISPLAY 0.872340 (-7748 5275);
PAINT GREEN (-7748 5275);
DISPLAY INVISIBLE (-7748 5275);
FORCEADD TAP..1
R 2
(-7750 5225);
FORCEPROP 3 LASTPIN (-7700 5225) SIG_NAME M_A_CPU0_SA_CA<2>
J 0
(-7690 5235);
DISPLAY 0.659574 (-7690 5235);
PAINT MONO (-7690 5235);
DISPLAY INVISIBLE (-7690 5235);
FORCEPROP 1 LASTPIN (-7700 5225) BN 2
J 2
(-7688 5233);
DISPLAY 0.489362 (-7688 5233);
PAINT GREEN (-7688 5233);
FORCEPROP 2 LAST CDS_LIB mstr_standard
J 0
(-7750 5225);
DISPLAY 0.723404 (-7750 5225);
PAINT MONO (-7750 5225);
DISPLAY INVISIBLE (-7750 5225);
FORCEPROP 1 LAST BODY_TYPE PLUMBING
J 2
(-7750 5275);
DISPLAY 0.872340 (-7750 5275);
PAINT GREEN (-7750 5275);
DISPLAY INVISIBLE (-7750 5275);
FORCEPROP 1 LAST HDL_TAP TRUE
J 2
(-8075 5100);
DISPLAY 0.872340 (-8075 5100);
DISPLAY INVISIBLE (-8075 5100);
FORCEPROP 1 LAST PATH I231
J 2
(-7748 5225);
DISPLAY 0.872340 (-7748 5225);
PAINT GREEN (-7748 5225);
DISPLAY INVISIBLE (-7748 5225);
FORCEADD TAP..1
R 2
(-7750 5175);
FORCEPROP 3 LASTPIN (-7700 5175) SIG_NAME M_A_CPU0_SA_CA<1>
J 0
(-7690 5185);
DISPLAY 0.659574 (-7690 5185);
PAINT MONO (-7690 5185);
DISPLAY INVISIBLE (-7690 5185);
FORCEPROP 1 LASTPIN (-7700 5175) BN 1
J 2
(-7688 5183);
DISPLAY 0.489362 (-7688 5183);
PAINT GREEN (-7688 5183);
FORCEPROP 2 LAST CDS_LIB mstr_standard
J 0
(-7750 5175);
DISPLAY 0.723404 (-7750 5175);
PAINT MONO (-7750 5175);
DISPLAY INVISIBLE (-7750 5175);
FORCEPROP 1 LAST BODY_TYPE PLUMBING
J 2
(-7750 5225);
DISPLAY 0.872340 (-7750 5225);
PAINT GREEN (-7750 5225);
DISPLAY INVISIBLE (-7750 5225);
FORCEPROP 1 LAST HDL_TAP TRUE
J 2
(-8075 5050);
DISPLAY 0.872340 (-8075 5050);
DISPLAY INVISIBLE (-8075 5050);
FORCEPROP 1 LAST PATH I232
J 2
(-7748 5175);
DISPLAY 0.872340 (-7748 5175);
PAINT GREEN (-7748 5175);
DISPLAY INVISIBLE (-7748 5175);
FORCEADD TAP..1
R 2
(-7750 5125);
FORCEPROP 3 LASTPIN (-7700 5125) SIG_NAME M_A_CPU0_SA_CA<0>
J 0
(-7690 5135);
DISPLAY 0.659574 (-7690 5135);
PAINT MONO (-7690 5135);
DISPLAY INVISIBLE (-7690 5135);
FORCEPROP 1 LASTPIN (-7700 5125) BN 0
J 2
(-7688 5133);
DISPLAY 0.489362 (-7688 5133);
PAINT GREEN (-7688 5133);
FORCEPROP 2 LAST CDS_LIB mstr_standard
J 0
(-7750 5125);
DISPLAY 0.723404 (-7750 5125);
PAINT MONO (-7750 5125);
DISPLAY INVISIBLE (-7750 5125);
FORCEPROP 1 LAST BODY_TYPE PLUMBING
J 2
(-7750 5175);
DISPLAY 0.872340 (-7750 5175);
PAINT GREEN (-7750 5175);
DISPLAY INVISIBLE (-7750 5175);
FORCEPROP 1 LAST HDL_TAP TRUE
J 2
(-8075 5000);
DISPLAY 0.872340 (-8075 5000);
DISPLAY INVISIBLE (-8075 5000);
FORCEPROP 1 LAST PATH I233
J 2
(-7748 5125);
DISPLAY 0.872340 (-7748 5125);
PAINT GREEN (-7748 5125);
DISPLAY INVISIBLE (-7748 5125);
FORCEADD TAP..1
R 2
(-7750 5025);
FORCEPROP 3 LASTPIN (-7700 5025) SIG_NAME M_A_CPU0_SB_CA<6>
J 0
(-7690 5035);
DISPLAY 0.659574 (-7690 5035);
PAINT MONO (-7690 5035);
DISPLAY INVISIBLE (-7690 5035);
FORCEPROP 1 LASTPIN (-7700 5025) BN 6
J 2
(-7688 5033);
DISPLAY 0.489362 (-7688 5033);
PAINT GREEN (-7688 5033);
FORCEPROP 2 LAST CDS_LIB mstr_standard
J 0
(-7750 5025);
DISPLAY 0.723404 (-7750 5025);
PAINT MONO (-7750 5025);
DISPLAY INVISIBLE (-7750 5025);
FORCEPROP 1 LAST BODY_TYPE PLUMBING
J 2
(-7750 5075);
DISPLAY 0.872340 (-7750 5075);
PAINT GREEN (-7750 5075);
DISPLAY INVISIBLE (-7750 5075);
FORCEPROP 1 LAST HDL_TAP TRUE
J 2
(-8075 4900);
DISPLAY 0.872340 (-8075 4900);
DISPLAY INVISIBLE (-8075 4900);
FORCEPROP 1 LAST PATH I235
J 2
(-7748 5025);
DISPLAY 0.872340 (-7748 5025);
PAINT GREEN (-7748 5025);
DISPLAY INVISIBLE (-7748 5025);
FORCEADD TAP..1
R 2
(-7750 4975);
FORCEPROP 3 LASTPIN (-7700 4975) SIG_NAME M_A_CPU0_SB_CA<5>
J 0
(-7690 4985);
DISPLAY 0.659574 (-7690 4985);
PAINT MONO (-7690 4985);
DISPLAY INVISIBLE (-7690 4985);
FORCEPROP 1 LASTPIN (-7700 4975) BN 5
J 2
(-7688 4983);
DISPLAY 0.489362 (-7688 4983);
PAINT GREEN (-7688 4983);
FORCEPROP 2 LAST CDS_LIB mstr_standard
J 0
(-7750 4975);
DISPLAY 0.723404 (-7750 4975);
PAINT MONO (-7750 4975);
DISPLAY INVISIBLE (-7750 4975);
FORCEPROP 1 LAST BODY_TYPE PLUMBING
J 2
(-7750 5025);
DISPLAY 0.872340 (-7750 5025);
PAINT GREEN (-7750 5025);
DISPLAY INVISIBLE (-7750 5025);
FORCEPROP 1 LAST HDL_TAP TRUE
J 2
(-8075 4850);
DISPLAY 0.872340 (-8075 4850);
DISPLAY INVISIBLE (-8075 4850);
FORCEPROP 1 LAST PATH I236
J 2
(-7748 4975);
DISPLAY 0.872340 (-7748 4975);
PAINT GREEN (-7748 4975);
DISPLAY INVISIBLE (-7748 4975);
FORCEADD TAP..1
R 2
(-7750 4925);
FORCEPROP 3 LASTPIN (-7700 4925) SIG_NAME M_A_CPU0_SB_CA<4>
J 0
(-7690 4935);
DISPLAY 0.659574 (-7690 4935);
PAINT MONO (-7690 4935);
DISPLAY INVISIBLE (-7690 4935);
FORCEPROP 1 LASTPIN (-7700 4925) BN 4
J 2
(-7688 4933);
DISPLAY 0.489362 (-7688 4933);
PAINT GREEN (-7688 4933);
FORCEPROP 2 LAST CDS_LIB mstr_standard
J 0
(-7750 4925);
DISPLAY 0.723404 (-7750 4925);
PAINT MONO (-7750 4925);
DISPLAY INVISIBLE (-7750 4925);
FORCEPROP 1 LAST BODY_TYPE PLUMBING
J 2
(-7750 4975);
DISPLAY 0.872340 (-7750 4975);
PAINT GREEN (-7750 4975);
DISPLAY INVISIBLE (-7750 4975);
FORCEPROP 1 LAST HDL_TAP TRUE
J 2
(-8075 4800);
DISPLAY 0.872340 (-8075 4800);
DISPLAY INVISIBLE (-8075 4800);
FORCEPROP 1 LAST PATH I237
J 2
(-7748 4925);
DISPLAY 0.872340 (-7748 4925);
PAINT GREEN (-7748 4925);
DISPLAY INVISIBLE (-7748 4925);
FORCEADD TAP..1
R 2
(-7750 4825);
FORCEPROP 3 LASTPIN (-7700 4825) SIG_NAME M_A_CPU0_SB_CA<2>
J 0
(-7690 4835);
DISPLAY 0.659574 (-7690 4835);
PAINT MONO (-7690 4835);
DISPLAY INVISIBLE (-7690 4835);
FORCEPROP 1 LASTPIN (-7700 4825) BN 2
J 2
(-7688 4833);
DISPLAY 0.489362 (-7688 4833);
PAINT GREEN (-7688 4833);
FORCEPROP 2 LAST CDS_LIB mstr_standard
J 0
(-7750 4825);
DISPLAY 0.723404 (-7750 4825);
PAINT MONO (-7750 4825);
DISPLAY INVISIBLE (-7750 4825);
FORCEPROP 1 LAST BODY_TYPE PLUMBING
J 2
(-7750 4875);
DISPLAY 0.872340 (-7750 4875);
PAINT GREEN (-7750 4875);
DISPLAY INVISIBLE (-7750 4875);
FORCEPROP 1 LAST HDL_TAP TRUE
J 2
(-8075 4700);
DISPLAY 0.872340 (-8075 4700);
DISPLAY INVISIBLE (-8075 4700);
FORCEPROP 1 LAST PATH I238
J 2
(-7748 4825);
DISPLAY 0.872340 (-7748 4825);
PAINT GREEN (-7748 4825);
DISPLAY INVISIBLE (-7748 4825);
FORCEADD TAP..1
R 2
(-7750 4725);
FORCEPROP 3 LASTPIN (-7700 4725) SIG_NAME M_A_CPU0_SB_CA<0>
J 0
(-7690 4735);
DISPLAY 0.659574 (-7690 4735);
PAINT MONO (-7690 4735);
DISPLAY INVISIBLE (-7690 4735);
FORCEPROP 1 LASTPIN (-7700 4725) BN 0
J 2
(-7688 4733);
DISPLAY 0.489362 (-7688 4733);
PAINT GREEN (-7688 4733);
FORCEPROP 2 LAST CDS_LIB mstr_standard
J 0
(-7750 4725);
DISPLAY 0.723404 (-7750 4725);
PAINT MONO (-7750 4725);
DISPLAY INVISIBLE (-7750 4725);
FORCEPROP 1 LAST BODY_TYPE PLUMBING
J 2
(-7750 4775);
DISPLAY 0.872340 (-7750 4775);
PAINT GREEN (-7750 4775);
DISPLAY INVISIBLE (-7750 4775);
FORCEPROP 1 LAST HDL_TAP TRUE
J 2
(-8075 4600);
DISPLAY 0.872340 (-8075 4600);
DISPLAY INVISIBLE (-8075 4600);
FORCEPROP 1 LAST PATH I239
J 2
(-7748 4725);
DISPLAY 0.872340 (-7748 4725);
PAINT GREEN (-7748 4725);
DISPLAY INVISIBLE (-7748 4725);
FORCEADD TAP..1
R 2
(-7750 4775);
FORCEPROP 3 LASTPIN (-7700 4775) SIG_NAME M_A_CPU0_SB_CA<1>
J 0
(-7690 4785);
DISPLAY 0.659574 (-7690 4785);
PAINT MONO (-7690 4785);
DISPLAY INVISIBLE (-7690 4785);
FORCEPROP 1 LASTPIN (-7700 4775) BN 1
J 2
(-7688 4783);
DISPLAY 0.489362 (-7688 4783);
PAINT GREEN (-7688 4783);
FORCEPROP 2 LAST CDS_LIB mstr_standard
J 0
(-7750 4775);
DISPLAY 0.723404 (-7750 4775);
PAINT MONO (-7750 4775);
DISPLAY INVISIBLE (-7750 4775);
FORCEPROP 1 LAST BODY_TYPE PLUMBING
J 2
(-7750 4825);
DISPLAY 0.872340 (-7750 4825);
PAINT GREEN (-7750 4825);
DISPLAY INVISIBLE (-7750 4825);
FORCEPROP 1 LAST HDL_TAP TRUE
J 2
(-8075 4650);
DISPLAY 0.872340 (-8075 4650);
DISPLAY INVISIBLE (-8075 4650);
FORCEPROP 1 LAST PATH I240
J 2
(-7748 4775);
DISPLAY 0.872340 (-7748 4775);
PAINT GREEN (-7748 4775);
DISPLAY INVISIBLE (-7748 4775);
FORCEADD TAP..1
R 2
(-7750 4875);
FORCEPROP 3 LASTPIN (-7700 4875) SIG_NAME M_A_CPU0_SB_CA<3>
J 0
(-7690 4885);
DISPLAY 0.659574 (-7690 4885);
PAINT MONO (-7690 4885);
DISPLAY INVISIBLE (-7690 4885);
FORCEPROP 1 LASTPIN (-7700 4875) BN 3
J 2
(-7688 4883);
DISPLAY 0.489362 (-7688 4883);
PAINT GREEN (-7688 4883);
FORCEPROP 2 LAST CDS_LIB mstr_standard
J 0
(-7750 4875);
DISPLAY 0.723404 (-7750 4875);
PAINT MONO (-7750 4875);
DISPLAY INVISIBLE (-7750 4875);
FORCEPROP 1 LAST BODY_TYPE PLUMBING
J 2
(-7750 4925);
DISPLAY 0.872340 (-7750 4925);
PAINT GREEN (-7750 4925);
DISPLAY INVISIBLE (-7750 4925);
FORCEPROP 1 LAST HDL_TAP TRUE
J 2
(-8075 4750);
DISPLAY 0.872340 (-8075 4750);
DISPLAY INVISIBLE (-8075 4750);
FORCEPROP 1 LAST PATH I241
J 2
(-7748 4875);
DISPLAY 0.872340 (-7748 4875);
PAINT GREEN (-7748 4875);
DISPLAY INVISIBLE (-7748 4875);
FORCEADD OFFPAGE..1
(-8350 5475);
FORCEPROP 2 LAST $XR0 10 
J 0
(-8601 5475);
DISPLAY 0.638298 (-8601 5475);
PAINT MONO (-8601 5475);
FORCEPROP 2 LAST CDS_LIB mstr_standard
J 0
(-8350 5475);
DISPLAY 0.723404 (-8350 5475);
PAINT MONO (-8350 5475);
DISPLAY INVISIBLE (-8350 5475);
FORCEPROP 1 LAST OFFPAGE TRUE
J 0
(-8025 5350);
DISPLAY 0.872340 (-8025 5350);
PAINT GREEN (-8025 5350);
DISPLAY INVISIBLE (-8025 5350);
FORCEPROP 1 LAST COMMENT_BODY TRUE
J 0
(-8225 5375);
DISPLAY 0.872340 (-8225 5375);
PAINT GREEN (-8225 5375);
DISPLAY INVISIBLE (-8225 5375);
FORCEPROP 2 LAST PATH I243
J 0
(-8600 5525);
DISPLAY 0.808511 (-8600 5525);
DISPLAY INVISIBLE (-8600 5525);
FORCEADD OFFPAGE..1
(-8350 4175);
FORCEPROP 2 LAST $XR0 10 
J 0
(-8601 4175);
DISPLAY 0.638298 (-8601 4175);
PAINT MONO (-8601 4175);
FORCEPROP 2 LAST CDS_LIB mstr_standard
J 0
(-8350 4175);
DISPLAY 0.723404 (-8350 4175);
PAINT MONO (-8350 4175);
DISPLAY INVISIBLE (-8350 4175);
FORCEPROP 1 LAST OFFPAGE TRUE
J 0
(-8025 4050);
DISPLAY 0.872340 (-8025 4050);
PAINT GREEN (-8025 4050);
DISPLAY INVISIBLE (-8025 4050);
FORCEPROP 1 LAST COMMENT_BODY TRUE
J 0
(-8225 4075);
DISPLAY 0.872340 (-8225 4075);
PAINT GREEN (-8225 4075);
DISPLAY INVISIBLE (-8225 4075);
FORCEPROP 2 LAST PATH I252
J 0
(-8600 4225);
DISPLAY 0.808511 (-8600 4225);
DISPLAY INVISIBLE (-8600 4225);
FORCEADD OFFPAGE..1
(-8350 4125);
FORCEPROP 2 LAST $XR0 10 
J 0
(-8601 4125);
DISPLAY 0.638298 (-8601 4125);
PAINT MONO (-8601 4125);
FORCEPROP 2 LAST CDS_LIB mstr_standard
J 0
(-8350 4125);
DISPLAY 0.808511 (-8350 4125);
DISPLAY INVISIBLE (-8350 4125);
FORCEPROP 1 LAST OFFPAGE TRUE
J 0
(-8025 4000);
DISPLAY 0.872340 (-8025 4000);
PAINT GREEN (-8025 4000);
DISPLAY INVISIBLE (-8025 4000);
FORCEPROP 1 LAST COMMENT_BODY TRUE
J 0
(-8225 4025);
DISPLAY 0.872340 (-8225 4025);
PAINT GREEN (-8225 4025);
DISPLAY INVISIBLE (-8225 4025);
FORCEPROP 2 LAST PATH I253
J 0
(-8300 4200);
DISPLAY 0.808511 (-8300 4200);
DISPLAY INVISIBLE (-8300 4200);
FORCEADD OFFPAGE..1
(-8350 4575);
FORCEPROP 2 LAST $XR0 10 
J 0
(-8601 4575);
DISPLAY 0.638298 (-8601 4575);
PAINT MONO (-8601 4575);
FORCEPROP 2 LAST CDS_LIB mstr_standard
J 0
(-8350 4575);
DISPLAY 0.808511 (-8350 4575);
DISPLAY INVISIBLE (-8350 4575);
FORCEPROP 1 LAST OFFPAGE TRUE
J 0
(-8025 4450);
DISPLAY 0.872340 (-8025 4450);
PAINT GREEN (-8025 4450);
DISPLAY INVISIBLE (-8025 4450);
FORCEPROP 1 LAST COMMENT_BODY TRUE
J 0
(-8225 4475);
DISPLAY 0.872340 (-8225 4475);
PAINT GREEN (-8225 4475);
DISPLAY INVISIBLE (-8225 4475);
FORCEPROP 2 LAST PATH I256
J 0
(-8300 4650);
DISPLAY 0.808511 (-8300 4650);
DISPLAY INVISIBLE (-8300 4650);
FORCEADD OFFPAGE..1
(-8350 4625);
FORCEPROP 2 LAST $XR0 10 
J 0
(-8601 4625);
DISPLAY 0.638298 (-8601 4625);
PAINT MONO (-8601 4625);
FORCEPROP 2 LAST CDS_LIB mstr_standard
J 0
(-8350 4625);
DISPLAY 0.723404 (-8350 4625);
PAINT MONO (-8350 4625);
DISPLAY INVISIBLE (-8350 4625);
FORCEPROP 1 LAST OFFPAGE TRUE
J 0
(-8025 4500);
DISPLAY 0.872340 (-8025 4500);
PAINT GREEN (-8025 4500);
DISPLAY INVISIBLE (-8025 4500);
FORCEPROP 1 LAST COMMENT_BODY TRUE
J 0
(-8225 4525);
DISPLAY 0.872340 (-8225 4525);
PAINT GREEN (-8225 4525);
DISPLAY INVISIBLE (-8225 4525);
FORCEPROP 2 LAST PATH I257
J 0
(-8300 4700);
DISPLAY 0.808511 (-8300 4700);
DISPLAY INVISIBLE (-8300 4700);
FORCEADD OFFPAGE..1
(-8350 4425);
FORCEPROP 2 LAST $XR0 10 
J 0
(-8601 4425);
DISPLAY 0.638298 (-8601 4425);
PAINT MONO (-8601 4425);
FORCEPROP 2 LAST CDS_LIB mstr_standard
J 0
(-8350 4425);
DISPLAY 0.808511 (-8350 4425);
DISPLAY INVISIBLE (-8350 4425);
FORCEPROP 1 LAST OFFPAGE TRUE
J 0
(-8025 4300);
DISPLAY 0.872340 (-8025 4300);
PAINT GREEN (-8025 4300);
DISPLAY INVISIBLE (-8025 4300);
FORCEPROP 1 LAST COMMENT_BODY TRUE
J 0
(-8225 4325);
DISPLAY 0.872340 (-8225 4325);
PAINT GREEN (-8225 4325);
DISPLAY INVISIBLE (-8225 4325);
FORCEPROP 2 LAST PATH I258
J 0
(-8300 4500);
DISPLAY 0.808511 (-8300 4500);
DISPLAY INVISIBLE (-8300 4500);
FORCEADD OFFPAGE..1
(-8350 4475);
FORCEPROP 2 LAST $XR0 10 
J 0
(-8601 4475);
DISPLAY 0.638298 (-8601 4475);
PAINT MONO (-8601 4475);
FORCEPROP 2 LAST CDS_LIB mstr_standard
J 0
(-8350 4475);
DISPLAY 0.723404 (-8350 4475);
PAINT MONO (-8350 4475);
DISPLAY INVISIBLE (-8350 4475);
FORCEPROP 1 LAST OFFPAGE TRUE
J 0
(-8025 4350);
DISPLAY 0.872340 (-8025 4350);
PAINT GREEN (-8025 4350);
DISPLAY INVISIBLE (-8025 4350);
FORCEPROP 1 LAST COMMENT_BODY TRUE
J 0
(-8225 4375);
DISPLAY 0.872340 (-8225 4375);
PAINT GREEN (-8225 4375);
DISPLAY INVISIBLE (-8225 4375);
FORCEPROP 2 LAST PATH I259
J 0
(-8300 4550);
DISPLAY 0.808511 (-8300 4550);
DISPLAY INVISIBLE (-8300 4550);
FORCEADD OFFPAGE..1
(-8350 4275);
FORCEPROP 2 LAST $XR0 10 
J 0
(-8601 4275);
DISPLAY 0.638298 (-8601 4275);
PAINT MONO (-8601 4275);
FORCEPROP 2 LAST CDS_LIB mstr_standard
J 0
(-8350 4275);
DISPLAY 0.808511 (-8350 4275);
DISPLAY INVISIBLE (-8350 4275);
FORCEPROP 1 LAST OFFPAGE TRUE
J 0
(-8025 4150);
DISPLAY 0.872340 (-8025 4150);
PAINT GREEN (-8025 4150);
DISPLAY INVISIBLE (-8025 4150);
FORCEPROP 1 LAST COMMENT_BODY TRUE
J 0
(-8225 4175);
DISPLAY 0.872340 (-8225 4175);
PAINT GREEN (-8225 4175);
DISPLAY INVISIBLE (-8225 4175);
FORCEPROP 2 LAST PATH I260
J 0
(-8300 4350);
DISPLAY 0.808511 (-8300 4350);
DISPLAY INVISIBLE (-8300 4350);
FORCEADD OFFPAGE..1
(-8350 4325);
FORCEPROP 2 LAST $XR0 10 
J 0
(-8601 4325);
DISPLAY 0.638298 (-8601 4325);
PAINT MONO (-8601 4325);
FORCEPROP 2 LAST CDS_LIB mstr_standard
J 0
(-8350 4325);
DISPLAY 0.723404 (-8350 4325);
PAINT MONO (-8350 4325);
DISPLAY INVISIBLE (-8350 4325);
FORCEPROP 1 LAST OFFPAGE TRUE
J 0
(-8025 4200);
DISPLAY 0.872340 (-8025 4200);
PAINT GREEN (-8025 4200);
DISPLAY INVISIBLE (-8025 4200);
FORCEPROP 1 LAST COMMENT_BODY TRUE
J 0
(-8225 4225);
DISPLAY 0.872340 (-8225 4225);
PAINT GREEN (-8225 4225);
DISPLAY INVISIBLE (-8225 4225);
FORCEPROP 2 LAST PATH I261
J 0
(-8300 4400);
DISPLAY 0.808511 (-8300 4400);
DISPLAY INVISIBLE (-8300 4400);
FORCEADD OFFPAGE..5
(-8350 2025);
FORCEPROP 2 LAST $XR0 10 
J 0
(-8574 2025);
DISPLAY 0.638298 (-8574 2025);
PAINT MONO (-8574 2025);
FORCEPROP 2 LAST CDS_LIB mstr_standard
J 0
(-8350 2025);
DISPLAY 0.808511 (-8350 2025);
DISPLAY INVISIBLE (-8350 2025);
FORCEPROP 1 LAST OFFPAGE TRUE
J 0
(-8025 1900);
DISPLAY 0.872340 (-8025 1900);
PAINT GREEN (-8025 1900);
DISPLAY INVISIBLE (-8025 1900);
FORCEPROP 1 LAST COMMENT_BODY TRUE
J 0
(-8250 1950);
DISPLAY 0.872340 (-8250 1950);
PAINT GREEN (-8250 1950);
DISPLAY INVISIBLE (-8250 1950);
FORCEPROP 2 LAST PATH I265
J 0
(-8300 2100);
DISPLAY 0.808511 (-8300 2100);
DISPLAY INVISIBLE (-8300 2100);
FORCEADD OFFPAGE..5
(-8350 1975);
FORCEPROP 2 LAST $XR0 10 
J 0
(-8574 1975);
DISPLAY 0.638298 (-8574 1975);
PAINT MONO (-8574 1975);
FORCEPROP 2 LAST CDS_LIB mstr_standard
J 0
(-8350 1975);
DISPLAY 0.808511 (-8350 1975);
DISPLAY INVISIBLE (-8350 1975);
FORCEPROP 1 LAST OFFPAGE TRUE
J 0
(-8025 1850);
DISPLAY 0.872340 (-8025 1850);
PAINT GREEN (-8025 1850);
DISPLAY INVISIBLE (-8025 1850);
FORCEPROP 1 LAST COMMENT_BODY TRUE
J 0
(-8250 1900);
DISPLAY 0.872340 (-8250 1900);
PAINT GREEN (-8250 1900);
DISPLAY INVISIBLE (-8250 1900);
FORCEPROP 2 LAST PATH I266
J 0
(-8300 2050);
DISPLAY 0.808511 (-8300 2050);
DISPLAY INVISIBLE (-8300 2050);
FORCEADD OFFPAGE..1
(-8350 5075);
FORCEPROP 2 LAST $XR0 10 
J 0
(-8601 5075);
DISPLAY 0.638298 (-8601 5075);
PAINT MONO (-8601 5075);
FORCEPROP 2 LAST CDS_LIB mstr_standard
J 0
(-8350 5075);
DISPLAY 0.723404 (-8350 5075);
PAINT MONO (-8350 5075);
DISPLAY INVISIBLE (-8350 5075);
FORCEPROP 1 LAST OFFPAGE TRUE
J 0
(-8025 4950);
DISPLAY 0.872340 (-8025 4950);
PAINT GREEN (-8025 4950);
DISPLAY INVISIBLE (-8025 4950);
FORCEPROP 1 LAST COMMENT_BODY TRUE
J 0
(-8225 4975);
DISPLAY 0.872340 (-8225 4975);
PAINT GREEN (-8225 4975);
DISPLAY INVISIBLE (-8225 4975);
FORCEPROP 2 LAST PATH I366
J 0
(-8300 5150);
DISPLAY 0.808511 (-8300 5150);
DISPLAY INVISIBLE (-8300 5150);
FORCEADD TAP..1
R 2
(-7750 3575);
FORCEPROP 3 LASTPIN (-7700 3575) SIG_NAME M_A_CPU0_SB_CB<7>
J 0
(-7690 3585);
DISPLAY 0.659574 (-7690 3585);
PAINT MONO (-7690 3585);
DISPLAY INVISIBLE (-7690 3585);
FORCEPROP 1 LASTPIN (-7700 3575) BN 7
J 2
(-7688 3583);
DISPLAY 0.489362 (-7688 3583);
PAINT GREEN (-7688 3583);
FORCEPROP 2 LAST CDS_LIB mstr_standard
J 0
(-7750 3575);
DISPLAY 0.723404 (-7750 3575);
PAINT MONO (-7750 3575);
DISPLAY INVISIBLE (-7750 3575);
FORCEPROP 1 LAST BODY_TYPE PLUMBING
J 2
(-7750 3625);
DISPLAY 0.872340 (-7750 3625);
PAINT GREEN (-7750 3625);
DISPLAY INVISIBLE (-7750 3625);
FORCEPROP 1 LAST HDL_TAP TRUE
J 2
(-8075 3450);
DISPLAY 0.872340 (-8075 3450);
DISPLAY INVISIBLE (-8075 3450);
FORCEPROP 1 LAST PATH I367
J 2
(-7748 3575);
DISPLAY 0.872340 (-7748 3575);
PAINT GREEN (-7748 3575);
DISPLAY INVISIBLE (-7748 3575);
FORCEADD TAP..1
R 2
(-7750 3525);
FORCEPROP 3 LASTPIN (-7700 3525) SIG_NAME M_A_CPU0_SB_CB<6>
J 0
(-7690 3535);
DISPLAY 0.659574 (-7690 3535);
PAINT MONO (-7690 3535);
DISPLAY INVISIBLE (-7690 3535);
FORCEPROP 1 LASTPIN (-7700 3525) BN 6
J 2
(-7688 3533);
DISPLAY 0.489362 (-7688 3533);
PAINT GREEN (-7688 3533);
FORCEPROP 2 LAST CDS_LIB mstr_standard
J 0
(-7750 3525);
DISPLAY 0.723404 (-7750 3525);
PAINT MONO (-7750 3525);
DISPLAY INVISIBLE (-7750 3525);
FORCEPROP 1 LAST BODY_TYPE PLUMBING
J 2
(-7750 3575);
DISPLAY 0.872340 (-7750 3575);
PAINT GREEN (-7750 3575);
DISPLAY INVISIBLE (-7750 3575);
FORCEPROP 1 LAST HDL_TAP TRUE
J 2
(-8075 3400);
DISPLAY 0.872340 (-8075 3400);
DISPLAY INVISIBLE (-8075 3400);
FORCEPROP 1 LAST PATH I368
J 2
(-7748 3525);
DISPLAY 0.872340 (-7748 3525);
PAINT GREEN (-7748 3525);
DISPLAY INVISIBLE (-7748 3525);
FORCEADD TAP..1
R 2
(-7750 3475);
FORCEPROP 3 LASTPIN (-7700 3475) SIG_NAME M_A_CPU0_SB_CB<5>
J 0
(-7690 3485);
DISPLAY 0.659574 (-7690 3485);
PAINT MONO (-7690 3485);
DISPLAY INVISIBLE (-7690 3485);
FORCEPROP 1 LASTPIN (-7700 3475) BN 5
J 2
(-7688 3483);
DISPLAY 0.489362 (-7688 3483);
PAINT GREEN (-7688 3483);
FORCEPROP 2 LAST CDS_LIB mstr_standard
J 0
(-7750 3475);
DISPLAY 0.723404 (-7750 3475);
PAINT MONO (-7750 3475);
DISPLAY INVISIBLE (-7750 3475);
FORCEPROP 1 LAST BODY_TYPE PLUMBING
J 2
(-7750 3525);
DISPLAY 0.872340 (-7750 3525);
PAINT GREEN (-7750 3525);
DISPLAY INVISIBLE (-7750 3525);
FORCEPROP 1 LAST HDL_TAP TRUE
J 2
(-8075 3350);
DISPLAY 0.872340 (-8075 3350);
DISPLAY INVISIBLE (-8075 3350);
FORCEPROP 1 LAST PATH I369
J 2
(-7748 3475);
DISPLAY 0.872340 (-7748 3475);
PAINT GREEN (-7748 3475);
DISPLAY INVISIBLE (-7748 3475);
FORCEADD TAP..1
R 2
(-7750 3425);
FORCEPROP 3 LASTPIN (-7700 3425) SIG_NAME M_A_CPU0_SB_CB<4>
J 0
(-7690 3435);
DISPLAY 0.659574 (-7690 3435);
PAINT MONO (-7690 3435);
DISPLAY INVISIBLE (-7690 3435);
FORCEPROP 1 LASTPIN (-7700 3425) BN 4
J 2
(-7688 3433);
DISPLAY 0.489362 (-7688 3433);
PAINT GREEN (-7688 3433);
FORCEPROP 2 LAST CDS_LIB mstr_standard
J 0
(-7750 3425);
DISPLAY 0.723404 (-7750 3425);
PAINT MONO (-7750 3425);
DISPLAY INVISIBLE (-7750 3425);
FORCEPROP 1 LAST BODY_TYPE PLUMBING
J 2
(-7750 3475);
DISPLAY 0.872340 (-7750 3475);
PAINT GREEN (-7750 3475);
DISPLAY INVISIBLE (-7750 3475);
FORCEPROP 1 LAST HDL_TAP TRUE
J 2
(-8075 3300);
DISPLAY 0.872340 (-8075 3300);
DISPLAY INVISIBLE (-8075 3300);
FORCEPROP 1 LAST PATH I370
J 2
(-7748 3425);
DISPLAY 0.872340 (-7748 3425);
PAINT GREEN (-7748 3425);
DISPLAY INVISIBLE (-7748 3425);
FORCEADD TAP..1
R 2
(-7750 3375);
FORCEPROP 3 LASTPIN (-7700 3375) SIG_NAME M_A_CPU0_SB_CB<3>
J 0
(-7690 3385);
DISPLAY 0.659574 (-7690 3385);
PAINT MONO (-7690 3385);
DISPLAY INVISIBLE (-7690 3385);
FORCEPROP 1 LASTPIN (-7700 3375) BN 3
J 2
(-7688 3383);
DISPLAY 0.489362 (-7688 3383);
PAINT GREEN (-7688 3383);
FORCEPROP 2 LAST CDS_LIB mstr_standard
J 0
(-7750 3375);
DISPLAY 0.723404 (-7750 3375);
PAINT MONO (-7750 3375);
DISPLAY INVISIBLE (-7750 3375);
FORCEPROP 1 LAST BODY_TYPE PLUMBING
J 2
(-7750 3425);
DISPLAY 0.872340 (-7750 3425);
PAINT GREEN (-7750 3425);
DISPLAY INVISIBLE (-7750 3425);
FORCEPROP 1 LAST HDL_TAP TRUE
J 2
(-8075 3250);
DISPLAY 0.872340 (-8075 3250);
DISPLAY INVISIBLE (-8075 3250);
FORCEPROP 1 LAST PATH I371
J 2
(-7748 3375);
DISPLAY 0.872340 (-7748 3375);
PAINT GREEN (-7748 3375);
DISPLAY INVISIBLE (-7748 3375);
FORCEADD TAP..1
R 2
(-7750 3225);
FORCEPROP 3 LASTPIN (-7700 3225) SIG_NAME M_A_CPU0_SB_CB<0>
J 0
(-7690 3235);
DISPLAY 0.659574 (-7690 3235);
PAINT MONO (-7690 3235);
DISPLAY INVISIBLE (-7690 3235);
FORCEPROP 1 LASTPIN (-7700 3225) BN 0
J 2
(-7688 3233);
DISPLAY 0.489362 (-7688 3233);
PAINT GREEN (-7688 3233);
FORCEPROP 2 LAST CDS_LIB mstr_standard
J 0
(-7750 3225);
DISPLAY 0.723404 (-7750 3225);
PAINT MONO (-7750 3225);
DISPLAY INVISIBLE (-7750 3225);
FORCEPROP 1 LAST BODY_TYPE PLUMBING
J 2
(-7750 3275);
DISPLAY 0.872340 (-7750 3275);
PAINT GREEN (-7750 3275);
DISPLAY INVISIBLE (-7750 3275);
FORCEPROP 1 LAST HDL_TAP TRUE
J 2
(-8075 3100);
DISPLAY 0.872340 (-8075 3100);
DISPLAY INVISIBLE (-8075 3100);
FORCEPROP 1 LAST PATH I372
J 2
(-7748 3225);
DISPLAY 0.872340 (-7748 3225);
PAINT GREEN (-7748 3225);
DISPLAY INVISIBLE (-7748 3225);
FORCEADD TAP..1
R 2
(-7750 3275);
FORCEPROP 3 LASTPIN (-7700 3275) SIG_NAME M_A_CPU0_SB_CB<1>
J 0
(-7690 3285);
DISPLAY 0.659574 (-7690 3285);
PAINT MONO (-7690 3285);
DISPLAY INVISIBLE (-7690 3285);
FORCEPROP 1 LASTPIN (-7700 3275) BN 1
J 2
(-7688 3283);
DISPLAY 0.489362 (-7688 3283);
PAINT GREEN (-7688 3283);
FORCEPROP 2 LAST CDS_LIB mstr_standard
J 0
(-7750 3275);
DISPLAY 0.723404 (-7750 3275);
PAINT MONO (-7750 3275);
DISPLAY INVISIBLE (-7750 3275);
FORCEPROP 1 LAST BODY_TYPE PLUMBING
J 2
(-7750 3325);
DISPLAY 0.872340 (-7750 3325);
PAINT GREEN (-7750 3325);
DISPLAY INVISIBLE (-7750 3325);
FORCEPROP 1 LAST HDL_TAP TRUE
J 2
(-8075 3150);
DISPLAY 0.872340 (-8075 3150);
DISPLAY INVISIBLE (-8075 3150);
FORCEPROP 1 LAST PATH I373
J 2
(-7748 3275);
DISPLAY 0.872340 (-7748 3275);
PAINT GREEN (-7748 3275);
DISPLAY INVISIBLE (-7748 3275);
FORCEADD TAP..1
R 2
(-7750 3325);
FORCEPROP 3 LASTPIN (-7700 3325) SIG_NAME M_A_CPU0_SB_CB<2>
J 0
(-7690 3335);
DISPLAY 0.659574 (-7690 3335);
PAINT MONO (-7690 3335);
DISPLAY INVISIBLE (-7690 3335);
FORCEPROP 1 LASTPIN (-7700 3325) BN 2
J 2
(-7688 3333);
DISPLAY 0.489362 (-7688 3333);
PAINT GREEN (-7688 3333);
FORCEPROP 2 LAST CDS_LIB mstr_standard
J 0
(-7750 3325);
DISPLAY 0.723404 (-7750 3325);
PAINT MONO (-7750 3325);
DISPLAY INVISIBLE (-7750 3325);
FORCEPROP 1 LAST BODY_TYPE PLUMBING
J 2
(-7750 3375);
DISPLAY 0.872340 (-7750 3375);
PAINT GREEN (-7750 3375);
DISPLAY INVISIBLE (-7750 3375);
FORCEPROP 1 LAST HDL_TAP TRUE
J 2
(-8075 3200);
DISPLAY 0.872340 (-8075 3200);
DISPLAY INVISIBLE (-8075 3200);
FORCEPROP 1 LAST PATH I374
J 2
(-7748 3325);
DISPLAY 0.872340 (-7748 3325);
PAINT GREEN (-7748 3325);
DISPLAY INVISIBLE (-7748 3325);
FORCEADD OFFPAGE..6
(-8350 3625);
FORCEPROP 2 LAST $XR0 10 
J 0
(-8629 3625);
DISPLAY 0.638298 (-8629 3625);
PAINT MONO (-8629 3625);
FORCEPROP 2 LAST CDS_LIB mstr_standard
J 0
(-8350 3625);
DISPLAY 0.723404 (-8350 3625);
PAINT MONO (-8350 3625);
DISPLAY INVISIBLE (-8350 3625);
FORCEPROP 1 LAST OFFPAGE TRUE
J 0
(-8025 3500);
DISPLAY 0.872340 (-8025 3500);
PAINT GREEN (-8025 3500);
DISPLAY INVISIBLE (-8025 3500);
FORCEPROP 1 LAST COMMENT_BODY TRUE
J 0
(-8250 3550);
DISPLAY 0.872340 (-8250 3550);
PAINT GREEN (-8250 3550);
DISPLAY INVISIBLE (-8250 3550);
FORCEPROP 2 LAST PATH I376
J 0
(-8300 3700);
DISPLAY 0.808511 (-8300 3700);
DISPLAY INVISIBLE (-8300 3700);
FORCEADD OFFPAGE..1
(-8350 3125);
FORCEPROP 2 LAST $XR0 10 
J 0
(-8601 3125);
DISPLAY 0.638298 (-8601 3125);
PAINT MONO (-8601 3125);
FORCEPROP 2 LAST CDS_LIB mstr_standard
J 0
(-8350 3125);
DISPLAY 0.808511 (-8350 3125);
DISPLAY INVISIBLE (-8350 3125);
FORCEPROP 1 LAST OFFPAGE TRUE
J 0
(-8025 3000);
DISPLAY 0.872340 (-8025 3000);
PAINT GREEN (-8025 3000);
DISPLAY INVISIBLE (-8025 3000);
FORCEPROP 1 LAST COMMENT_BODY TRUE
J 0
(-8225 3025);
DISPLAY 0.872340 (-8225 3025);
PAINT GREEN (-8225 3025);
DISPLAY INVISIBLE (-8225 3025);
FORCEPROP 2 LAST PATH I378
J 0
(-8550 3350);
DISPLAY 0.808511 (-8550 3350);
DISPLAY INVISIBLE (-8550 3350);
FORCEADD TAP..1
(-6050 2275);
FORCEPROP 3 LASTPIN (-6100 2275) SIG_NAME M_A_CPU0_SB_DQ<1>
J 0
(-6090 2285);
DISPLAY 0.659574 (-6090 2285);
PAINT MONO (-6090 2285);
DISPLAY INVISIBLE (-6090 2285);
FORCEPROP 1 LASTPIN (-6100 2275) BN 1
J 0
(-6112 2283);
DISPLAY 0.489362 (-6112 2283);
PAINT GREEN (-6112 2283);
FORCEPROP 2 LAST CDS_LIB mstr_standard
J 0
(-6050 2275);
DISPLAY 0.723404 (-6050 2275);
PAINT MONO (-6050 2275);
DISPLAY INVISIBLE (-6050 2275);
FORCEPROP 1 LAST BODY_TYPE PLUMBING
J 0
(-6050 2325);
DISPLAY 0.872340 (-6050 2325);
PAINT GREEN (-6050 2325);
DISPLAY INVISIBLE (-6050 2325);
FORCEPROP 1 LAST HDL_TAP TRUE
J 0
(-5725 2150);
DISPLAY 0.872340 (-5725 2150);
DISPLAY INVISIBLE (-5725 2150);
FORCEPROP 1 LAST PATH I383
J 0
(-6052 2275);
DISPLAY 0.872340 (-6052 2275);
PAINT GREEN (-6052 2275);
DISPLAY INVISIBLE (-6052 2275);
FORCEADD TAP..1
(-6050 2225);
FORCEPROP 3 LASTPIN (-6100 2225) SIG_NAME M_A_CPU0_SB_DQ<0>
J 0
(-6090 2235);
DISPLAY 0.659574 (-6090 2235);
PAINT MONO (-6090 2235);
DISPLAY INVISIBLE (-6090 2235);
FORCEPROP 1 LASTPIN (-6100 2225) BN 0
J 0
(-6112 2233);
DISPLAY 0.489362 (-6112 2233);
PAINT GREEN (-6112 2233);
FORCEPROP 2 LAST CDS_LIB mstr_standard
J 0
(-6050 2225);
DISPLAY 0.723404 (-6050 2225);
PAINT MONO (-6050 2225);
DISPLAY INVISIBLE (-6050 2225);
FORCEPROP 1 LAST BODY_TYPE PLUMBING
J 0
(-6050 2275);
DISPLAY 0.872340 (-6050 2275);
PAINT GREEN (-6050 2275);
DISPLAY INVISIBLE (-6050 2275);
FORCEPROP 1 LAST HDL_TAP TRUE
J 0
(-5725 2100);
DISPLAY 0.872340 (-5725 2100);
DISPLAY INVISIBLE (-5725 2100);
FORCEPROP 1 LAST PATH I384
J 0
(-6052 2225);
DISPLAY 0.872340 (-6052 2225);
PAINT GREEN (-6052 2225);
DISPLAY INVISIBLE (-6052 2225);
FORCEADD TAP..1
(-6050 2325);
FORCEPROP 3 LASTPIN (-6100 2325) SIG_NAME M_A_CPU0_SB_DQ<2>
J 0
(-6090 2335);
DISPLAY 0.659574 (-6090 2335);
PAINT MONO (-6090 2335);
DISPLAY INVISIBLE (-6090 2335);
FORCEPROP 1 LASTPIN (-6100 2325) BN 2
J 0
(-6112 2333);
DISPLAY 0.489362 (-6112 2333);
PAINT GREEN (-6112 2333);
FORCEPROP 2 LAST CDS_LIB mstr_standard
J 0
(-6050 2325);
DISPLAY 0.723404 (-6050 2325);
PAINT MONO (-6050 2325);
DISPLAY INVISIBLE (-6050 2325);
FORCEPROP 1 LAST BODY_TYPE PLUMBING
J 0
(-6050 2375);
DISPLAY 0.872340 (-6050 2375);
PAINT GREEN (-6050 2375);
DISPLAY INVISIBLE (-6050 2375);
FORCEPROP 1 LAST HDL_TAP TRUE
J 0
(-5725 2200);
DISPLAY 0.872340 (-5725 2200);
DISPLAY INVISIBLE (-5725 2200);
FORCEPROP 1 LAST PATH I385
J 0
(-6052 2325);
DISPLAY 0.872340 (-6052 2325);
PAINT GREEN (-6052 2325);
DISPLAY INVISIBLE (-6052 2325);
FORCEADD TAP..1
(-6050 2375);
FORCEPROP 3 LASTPIN (-6100 2375) SIG_NAME M_A_CPU0_SB_DQ<3>
J 0
(-6090 2385);
DISPLAY 0.659574 (-6090 2385);
PAINT MONO (-6090 2385);
DISPLAY INVISIBLE (-6090 2385);
FORCEPROP 1 LASTPIN (-6100 2375) BN 3
J 0
(-6112 2383);
DISPLAY 0.489362 (-6112 2383);
PAINT GREEN (-6112 2383);
FORCEPROP 2 LAST CDS_LIB mstr_standard
J 0
(-6050 2375);
DISPLAY 0.723404 (-6050 2375);
PAINT MONO (-6050 2375);
DISPLAY INVISIBLE (-6050 2375);
FORCEPROP 1 LAST BODY_TYPE PLUMBING
J 0
(-6050 2425);
DISPLAY 0.872340 (-6050 2425);
PAINT GREEN (-6050 2425);
DISPLAY INVISIBLE (-6050 2425);
FORCEPROP 1 LAST HDL_TAP TRUE
J 0
(-5725 2250);
DISPLAY 0.872340 (-5725 2250);
DISPLAY INVISIBLE (-5725 2250);
FORCEPROP 1 LAST PATH I386
J 0
(-6052 2375);
DISPLAY 0.872340 (-6052 2375);
PAINT GREEN (-6052 2375);
DISPLAY INVISIBLE (-6052 2375);
FORCEADD TAP..1
(-6050 2425);
FORCEPROP 3 LASTPIN (-6100 2425) SIG_NAME M_A_CPU0_SB_DQ<4>
J 0
(-6090 2435);
DISPLAY 0.659574 (-6090 2435);
PAINT MONO (-6090 2435);
DISPLAY INVISIBLE (-6090 2435);
FORCEPROP 1 LASTPIN (-6100 2425) BN 4
J 0
(-6112 2433);
DISPLAY 0.489362 (-6112 2433);
PAINT GREEN (-6112 2433);
FORCEPROP 2 LAST CDS_LIB mstr_standard
J 0
(-6050 2425);
DISPLAY 0.723404 (-6050 2425);
PAINT MONO (-6050 2425);
DISPLAY INVISIBLE (-6050 2425);
FORCEPROP 1 LAST BODY_TYPE PLUMBING
J 0
(-6050 2475);
DISPLAY 0.872340 (-6050 2475);
PAINT GREEN (-6050 2475);
DISPLAY INVISIBLE (-6050 2475);
FORCEPROP 1 LAST HDL_TAP TRUE
J 0
(-5725 2300);
DISPLAY 0.872340 (-5725 2300);
DISPLAY INVISIBLE (-5725 2300);
FORCEPROP 1 LAST PATH I387
J 0
(-6052 2425);
DISPLAY 0.872340 (-6052 2425);
PAINT GREEN (-6052 2425);
DISPLAY INVISIBLE (-6052 2425);
FORCEADD TAP..1
(-6050 2475);
FORCEPROP 3 LASTPIN (-6100 2475) SIG_NAME M_A_CPU0_SB_DQ<5>
J 0
(-6090 2485);
DISPLAY 0.659574 (-6090 2485);
PAINT MONO (-6090 2485);
DISPLAY INVISIBLE (-6090 2485);
FORCEPROP 1 LASTPIN (-6100 2475) BN 5
J 0
(-6112 2483);
DISPLAY 0.489362 (-6112 2483);
PAINT GREEN (-6112 2483);
FORCEPROP 2 LAST CDS_LIB mstr_standard
J 0
(-6050 2475);
DISPLAY 0.723404 (-6050 2475);
PAINT MONO (-6050 2475);
DISPLAY INVISIBLE (-6050 2475);
FORCEPROP 1 LAST BODY_TYPE PLUMBING
J 0
(-6050 2525);
DISPLAY 0.872340 (-6050 2525);
PAINT GREEN (-6050 2525);
DISPLAY INVISIBLE (-6050 2525);
FORCEPROP 1 LAST HDL_TAP TRUE
J 0
(-5725 2350);
DISPLAY 0.872340 (-5725 2350);
DISPLAY INVISIBLE (-5725 2350);
FORCEPROP 1 LAST PATH I388
J 0
(-6052 2475);
DISPLAY 0.872340 (-6052 2475);
PAINT GREEN (-6052 2475);
DISPLAY INVISIBLE (-6052 2475);
FORCEADD TAP..1
(-6050 2525);
FORCEPROP 3 LASTPIN (-6100 2525) SIG_NAME M_A_CPU0_SB_DQ<6>
J 0
(-6090 2535);
DISPLAY 0.659574 (-6090 2535);
PAINT MONO (-6090 2535);
DISPLAY INVISIBLE (-6090 2535);
FORCEPROP 1 LASTPIN (-6100 2525) BN 6
J 0
(-6112 2533);
DISPLAY 0.489362 (-6112 2533);
PAINT GREEN (-6112 2533);
FORCEPROP 2 LAST CDS_LIB mstr_standard
J 0
(-6050 2525);
DISPLAY 0.723404 (-6050 2525);
PAINT MONO (-6050 2525);
DISPLAY INVISIBLE (-6050 2525);
FORCEPROP 1 LAST BODY_TYPE PLUMBING
J 0
(-6050 2575);
DISPLAY 0.872340 (-6050 2575);
PAINT GREEN (-6050 2575);
DISPLAY INVISIBLE (-6050 2575);
FORCEPROP 1 LAST HDL_TAP TRUE
J 0
(-5725 2400);
DISPLAY 0.872340 (-5725 2400);
DISPLAY INVISIBLE (-5725 2400);
FORCEPROP 1 LAST PATH I389
J 0
(-6052 2525);
DISPLAY 0.872340 (-6052 2525);
PAINT GREEN (-6052 2525);
DISPLAY INVISIBLE (-6052 2525);
FORCEADD TAP..1
(-6050 2575);
FORCEPROP 3 LASTPIN (-6100 2575) SIG_NAME M_A_CPU0_SB_DQ<7>
J 0
(-6090 2585);
DISPLAY 0.659574 (-6090 2585);
PAINT MONO (-6090 2585);
DISPLAY INVISIBLE (-6090 2585);
FORCEPROP 1 LASTPIN (-6100 2575) BN 7
J 0
(-6112 2583);
DISPLAY 0.489362 (-6112 2583);
PAINT GREEN (-6112 2583);
FORCEPROP 2 LAST CDS_LIB mstr_standard
J 0
(-6050 2575);
DISPLAY 0.723404 (-6050 2575);
PAINT MONO (-6050 2575);
DISPLAY INVISIBLE (-6050 2575);
FORCEPROP 1 LAST BODY_TYPE PLUMBING
J 0
(-6050 2625);
DISPLAY 0.872340 (-6050 2625);
PAINT GREEN (-6050 2625);
DISPLAY INVISIBLE (-6050 2625);
FORCEPROP 1 LAST HDL_TAP TRUE
J 0
(-5725 2450);
DISPLAY 0.872340 (-5725 2450);
DISPLAY INVISIBLE (-5725 2450);
FORCEPROP 1 LAST PATH I390
J 0
(-6052 2575);
DISPLAY 0.872340 (-6052 2575);
PAINT GREEN (-6052 2575);
DISPLAY INVISIBLE (-6052 2575);
FORCEADD TAP..1
(-6050 2625);
FORCEPROP 3 LASTPIN (-6100 2625) SIG_NAME M_A_CPU0_SB_DQ<8>
J 0
(-6090 2635);
DISPLAY 0.659574 (-6090 2635);
PAINT MONO (-6090 2635);
DISPLAY INVISIBLE (-6090 2635);
FORCEPROP 1 LASTPIN (-6100 2625) BN 8
J 0
(-6112 2633);
DISPLAY 0.489362 (-6112 2633);
PAINT GREEN (-6112 2633);
FORCEPROP 2 LAST CDS_LIB mstr_standard
J 0
(-6050 2625);
DISPLAY 0.723404 (-6050 2625);
PAINT MONO (-6050 2625);
DISPLAY INVISIBLE (-6050 2625);
FORCEPROP 1 LAST BODY_TYPE PLUMBING
J 0
(-6050 2675);
DISPLAY 0.872340 (-6050 2675);
PAINT GREEN (-6050 2675);
DISPLAY INVISIBLE (-6050 2675);
FORCEPROP 1 LAST HDL_TAP TRUE
J 0
(-5725 2500);
DISPLAY 0.872340 (-5725 2500);
DISPLAY INVISIBLE (-5725 2500);
FORCEPROP 1 LAST PATH I391
J 0
(-6052 2625);
DISPLAY 0.872340 (-6052 2625);
PAINT GREEN (-6052 2625);
DISPLAY INVISIBLE (-6052 2625);
FORCEADD TAP..1
(-6050 2675);
FORCEPROP 3 LASTPIN (-6100 2675) SIG_NAME M_A_CPU0_SB_DQ<9>
J 0
(-6090 2685);
DISPLAY 0.659574 (-6090 2685);
PAINT MONO (-6090 2685);
DISPLAY INVISIBLE (-6090 2685);
FORCEPROP 1 LASTPIN (-6100 2675) BN 9
J 0
(-6112 2683);
DISPLAY 0.489362 (-6112 2683);
PAINT GREEN (-6112 2683);
FORCEPROP 2 LAST CDS_LIB mstr_standard
J 0
(-6050 2675);
DISPLAY 0.723404 (-6050 2675);
PAINT MONO (-6050 2675);
DISPLAY INVISIBLE (-6050 2675);
FORCEPROP 1 LAST BODY_TYPE PLUMBING
J 0
(-6050 2725);
DISPLAY 0.872340 (-6050 2725);
PAINT GREEN (-6050 2725);
DISPLAY INVISIBLE (-6050 2725);
FORCEPROP 1 LAST HDL_TAP TRUE
J 0
(-5725 2550);
DISPLAY 0.872340 (-5725 2550);
DISPLAY INVISIBLE (-5725 2550);
FORCEPROP 1 LAST PATH I392
J 0
(-6052 2675);
DISPLAY 0.872340 (-6052 2675);
PAINT GREEN (-6052 2675);
DISPLAY INVISIBLE (-6052 2675);
FORCEADD TAP..1
(-6050 2725);
FORCEPROP 3 LASTPIN (-6100 2725) SIG_NAME M_A_CPU0_SB_DQ<10>
J 0
(-6090 2735);
DISPLAY 0.659574 (-6090 2735);
PAINT MONO (-6090 2735);
DISPLAY INVISIBLE (-6090 2735);
FORCEPROP 1 LASTPIN (-6100 2725) BN 10
J 0
(-6112 2733);
DISPLAY 0.489362 (-6112 2733);
PAINT GREEN (-6112 2733);
FORCEPROP 2 LAST CDS_LIB mstr_standard
J 0
(-6050 2725);
DISPLAY 0.723404 (-6050 2725);
PAINT MONO (-6050 2725);
DISPLAY INVISIBLE (-6050 2725);
FORCEPROP 1 LAST BODY_TYPE PLUMBING
J 0
(-6050 2775);
DISPLAY 0.872340 (-6050 2775);
PAINT GREEN (-6050 2775);
DISPLAY INVISIBLE (-6050 2775);
FORCEPROP 1 LAST HDL_TAP TRUE
J 0
(-5725 2600);
DISPLAY 0.872340 (-5725 2600);
DISPLAY INVISIBLE (-5725 2600);
FORCEPROP 1 LAST PATH I393
J 0
(-6052 2725);
DISPLAY 0.872340 (-6052 2725);
PAINT GREEN (-6052 2725);
DISPLAY INVISIBLE (-6052 2725);
FORCEADD TAP..1
(-6050 2825);
FORCEPROP 3 LASTPIN (-6100 2825) SIG_NAME M_A_CPU0_SB_DQ<12>
J 0
(-6090 2835);
DISPLAY 0.659574 (-6090 2835);
PAINT MONO (-6090 2835);
DISPLAY INVISIBLE (-6090 2835);
FORCEPROP 1 LASTPIN (-6100 2825) BN 12
J 0
(-6112 2833);
DISPLAY 0.489362 (-6112 2833);
PAINT GREEN (-6112 2833);
FORCEPROP 2 LAST CDS_LIB mstr_standard
J 0
(-6050 2825);
DISPLAY 0.723404 (-6050 2825);
PAINT MONO (-6050 2825);
DISPLAY INVISIBLE (-6050 2825);
FORCEPROP 1 LAST BODY_TYPE PLUMBING
J 0
(-6050 2875);
DISPLAY 0.872340 (-6050 2875);
PAINT GREEN (-6050 2875);
DISPLAY INVISIBLE (-6050 2875);
FORCEPROP 1 LAST HDL_TAP TRUE
J 0
(-5725 2700);
DISPLAY 0.872340 (-5725 2700);
DISPLAY INVISIBLE (-5725 2700);
FORCEPROP 1 LAST PATH I394
J 0
(-6052 2825);
DISPLAY 0.872340 (-6052 2825);
PAINT GREEN (-6052 2825);
DISPLAY INVISIBLE (-6052 2825);
FORCEADD TAP..1
(-6050 2775);
FORCEPROP 3 LASTPIN (-6100 2775) SIG_NAME M_A_CPU0_SB_DQ<11>
J 0
(-6090 2785);
DISPLAY 0.659574 (-6090 2785);
PAINT MONO (-6090 2785);
DISPLAY INVISIBLE (-6090 2785);
FORCEPROP 1 LASTPIN (-6100 2775) BN 11
J 0
(-6112 2783);
DISPLAY 0.489362 (-6112 2783);
PAINT GREEN (-6112 2783);
FORCEPROP 2 LAST CDS_LIB mstr_standard
J 0
(-6050 2775);
DISPLAY 0.723404 (-6050 2775);
PAINT MONO (-6050 2775);
DISPLAY INVISIBLE (-6050 2775);
FORCEPROP 1 LAST BODY_TYPE PLUMBING
J 0
(-6050 2825);
DISPLAY 0.872340 (-6050 2825);
PAINT GREEN (-6050 2825);
DISPLAY INVISIBLE (-6050 2825);
FORCEPROP 1 LAST HDL_TAP TRUE
J 0
(-5725 2650);
DISPLAY 0.872340 (-5725 2650);
DISPLAY INVISIBLE (-5725 2650);
FORCEPROP 1 LAST PATH I395
J 0
(-6052 2775);
DISPLAY 0.872340 (-6052 2775);
PAINT GREEN (-6052 2775);
DISPLAY INVISIBLE (-6052 2775);
FORCEADD TAP..1
(-6050 2875);
FORCEPROP 3 LASTPIN (-6100 2875) SIG_NAME M_A_CPU0_SB_DQ<13>
J 0
(-6090 2885);
DISPLAY 0.659574 (-6090 2885);
PAINT MONO (-6090 2885);
DISPLAY INVISIBLE (-6090 2885);
FORCEPROP 1 LASTPIN (-6100 2875) BN 13
J 0
(-6112 2883);
DISPLAY 0.489362 (-6112 2883);
PAINT GREEN (-6112 2883);
FORCEPROP 2 LAST CDS_LIB mstr_standard
J 0
(-6050 2875);
DISPLAY 0.723404 (-6050 2875);
PAINT MONO (-6050 2875);
DISPLAY INVISIBLE (-6050 2875);
FORCEPROP 1 LAST BODY_TYPE PLUMBING
J 0
(-6050 2925);
DISPLAY 0.872340 (-6050 2925);
PAINT GREEN (-6050 2925);
DISPLAY INVISIBLE (-6050 2925);
FORCEPROP 1 LAST HDL_TAP TRUE
J 0
(-5725 2750);
DISPLAY 0.872340 (-5725 2750);
DISPLAY INVISIBLE (-5725 2750);
FORCEPROP 1 LAST PATH I396
J 0
(-6052 2875);
DISPLAY 0.872340 (-6052 2875);
PAINT GREEN (-6052 2875);
DISPLAY INVISIBLE (-6052 2875);
FORCEADD TAP..1
(-6050 2975);
FORCEPROP 3 LASTPIN (-6100 2975) SIG_NAME M_A_CPU0_SB_DQ<15>
J 0
(-6090 2985);
DISPLAY 0.659574 (-6090 2985);
PAINT MONO (-6090 2985);
DISPLAY INVISIBLE (-6090 2985);
FORCEPROP 1 LASTPIN (-6100 2975) BN 15
J 0
(-6112 2983);
DISPLAY 0.489362 (-6112 2983);
PAINT GREEN (-6112 2983);
FORCEPROP 2 LAST CDS_LIB mstr_standard
J 0
(-6050 2975);
DISPLAY 0.723404 (-6050 2975);
PAINT MONO (-6050 2975);
DISPLAY INVISIBLE (-6050 2975);
FORCEPROP 1 LAST BODY_TYPE PLUMBING
J 0
(-6050 3025);
DISPLAY 0.872340 (-6050 3025);
PAINT GREEN (-6050 3025);
DISPLAY INVISIBLE (-6050 3025);
FORCEPROP 1 LAST HDL_TAP TRUE
J 0
(-5725 2850);
DISPLAY 0.872340 (-5725 2850);
DISPLAY INVISIBLE (-5725 2850);
FORCEPROP 1 LAST PATH I397
J 0
(-6052 2975);
DISPLAY 0.872340 (-6052 2975);
PAINT GREEN (-6052 2975);
DISPLAY INVISIBLE (-6052 2975);
FORCEADD TAP..1
(-6050 2925);
FORCEPROP 3 LASTPIN (-6100 2925) SIG_NAME M_A_CPU0_SB_DQ<14>
J 0
(-6090 2935);
DISPLAY 0.659574 (-6090 2935);
PAINT MONO (-6090 2935);
DISPLAY INVISIBLE (-6090 2935);
FORCEPROP 1 LASTPIN (-6100 2925) BN 14
J 0
(-6112 2933);
DISPLAY 0.489362 (-6112 2933);
PAINT GREEN (-6112 2933);
FORCEPROP 2 LAST CDS_LIB mstr_standard
J 0
(-6050 2925);
DISPLAY 0.723404 (-6050 2925);
PAINT MONO (-6050 2925);
DISPLAY INVISIBLE (-6050 2925);
FORCEPROP 1 LAST BODY_TYPE PLUMBING
J 0
(-6050 2975);
DISPLAY 0.872340 (-6050 2975);
PAINT GREEN (-6050 2975);
DISPLAY INVISIBLE (-6050 2975);
FORCEPROP 1 LAST HDL_TAP TRUE
J 0
(-5725 2800);
DISPLAY 0.872340 (-5725 2800);
DISPLAY INVISIBLE (-5725 2800);
FORCEPROP 1 LAST PATH I398
J 0
(-6052 2925);
DISPLAY 0.872340 (-6052 2925);
PAINT GREEN (-6052 2925);
DISPLAY INVISIBLE (-6052 2925);
FORCEADD TAP..1
(-6050 3025);
FORCEPROP 3 LASTPIN (-6100 3025) SIG_NAME M_A_CPU0_SB_DQ<16>
J 0
(-6090 3035);
DISPLAY 0.659574 (-6090 3035);
PAINT MONO (-6090 3035);
DISPLAY INVISIBLE (-6090 3035);
FORCEPROP 1 LASTPIN (-6100 3025) BN 16
J 0
(-6112 3033);
DISPLAY 0.489362 (-6112 3033);
PAINT GREEN (-6112 3033);
FORCEPROP 2 LAST CDS_LIB mstr_standard
J 0
(-6050 3025);
DISPLAY 0.723404 (-6050 3025);
PAINT MONO (-6050 3025);
DISPLAY INVISIBLE (-6050 3025);
FORCEPROP 1 LAST BODY_TYPE PLUMBING
J 0
(-6050 3075);
DISPLAY 0.872340 (-6050 3075);
PAINT GREEN (-6050 3075);
DISPLAY INVISIBLE (-6050 3075);
FORCEPROP 1 LAST HDL_TAP TRUE
J 0
(-5725 2900);
DISPLAY 0.872340 (-5725 2900);
DISPLAY INVISIBLE (-5725 2900);
FORCEPROP 1 LAST PATH I399
J 0
(-6052 3025);
DISPLAY 0.872340 (-6052 3025);
PAINT GREEN (-6052 3025);
DISPLAY INVISIBLE (-6052 3025);
FORCEADD TAP..1
(-6050 3075);
FORCEPROP 3 LASTPIN (-6100 3075) SIG_NAME M_A_CPU0_SB_DQ<17>
J 0
(-6090 3085);
DISPLAY 0.659574 (-6090 3085);
PAINT MONO (-6090 3085);
DISPLAY INVISIBLE (-6090 3085);
FORCEPROP 1 LASTPIN (-6100 3075) BN 17
J 0
(-6112 3083);
DISPLAY 0.489362 (-6112 3083);
PAINT GREEN (-6112 3083);
FORCEPROP 2 LAST CDS_LIB mstr_standard
J 0
(-6050 3075);
DISPLAY 0.723404 (-6050 3075);
PAINT MONO (-6050 3075);
DISPLAY INVISIBLE (-6050 3075);
FORCEPROP 1 LAST BODY_TYPE PLUMBING
J 0
(-6050 3125);
DISPLAY 0.872340 (-6050 3125);
PAINT GREEN (-6050 3125);
DISPLAY INVISIBLE (-6050 3125);
FORCEPROP 1 LAST HDL_TAP TRUE
J 0
(-5725 2950);
DISPLAY 0.872340 (-5725 2950);
DISPLAY INVISIBLE (-5725 2950);
FORCEPROP 1 LAST PATH I400
J 0
(-6052 3075);
DISPLAY 0.872340 (-6052 3075);
PAINT GREEN (-6052 3075);
DISPLAY INVISIBLE (-6052 3075);
FORCEADD TAP..1
(-6050 3125);
FORCEPROP 3 LASTPIN (-6100 3125) SIG_NAME M_A_CPU0_SB_DQ<18>
J 0
(-6090 3135);
DISPLAY 0.659574 (-6090 3135);
PAINT MONO (-6090 3135);
DISPLAY INVISIBLE (-6090 3135);
FORCEPROP 1 LASTPIN (-6100 3125) BN 18
J 0
(-6112 3133);
DISPLAY 0.489362 (-6112 3133);
PAINT GREEN (-6112 3133);
FORCEPROP 2 LAST CDS_LIB mstr_standard
J 0
(-6050 3125);
DISPLAY 0.723404 (-6050 3125);
PAINT MONO (-6050 3125);
DISPLAY INVISIBLE (-6050 3125);
FORCEPROP 1 LAST BODY_TYPE PLUMBING
J 0
(-6050 3175);
DISPLAY 0.872340 (-6050 3175);
PAINT GREEN (-6050 3175);
DISPLAY INVISIBLE (-6050 3175);
FORCEPROP 1 LAST HDL_TAP TRUE
J 0
(-5725 3000);
DISPLAY 0.872340 (-5725 3000);
DISPLAY INVISIBLE (-5725 3000);
FORCEPROP 1 LAST PATH I401
J 0
(-6052 3125);
DISPLAY 0.872340 (-6052 3125);
PAINT GREEN (-6052 3125);
DISPLAY INVISIBLE (-6052 3125);
FORCEADD TAP..1
(-6050 3175);
FORCEPROP 3 LASTPIN (-6100 3175) SIG_NAME M_A_CPU0_SB_DQ<19>
J 0
(-6090 3185);
DISPLAY 0.659574 (-6090 3185);
PAINT MONO (-6090 3185);
DISPLAY INVISIBLE (-6090 3185);
FORCEPROP 1 LASTPIN (-6100 3175) BN 19
J 0
(-6112 3183);
DISPLAY 0.489362 (-6112 3183);
PAINT GREEN (-6112 3183);
FORCEPROP 2 LAST CDS_LIB mstr_standard
J 0
(-6050 3175);
DISPLAY 0.723404 (-6050 3175);
PAINT MONO (-6050 3175);
DISPLAY INVISIBLE (-6050 3175);
FORCEPROP 1 LAST BODY_TYPE PLUMBING
J 0
(-6050 3225);
DISPLAY 0.872340 (-6050 3225);
PAINT GREEN (-6050 3225);
DISPLAY INVISIBLE (-6050 3225);
FORCEPROP 1 LAST HDL_TAP TRUE
J 0
(-5725 3050);
DISPLAY 0.872340 (-5725 3050);
DISPLAY INVISIBLE (-5725 3050);
FORCEPROP 1 LAST PATH I402
J 0
(-6052 3175);
DISPLAY 0.872340 (-6052 3175);
PAINT GREEN (-6052 3175);
DISPLAY INVISIBLE (-6052 3175);
FORCEADD TAP..1
(-6050 3375);
FORCEPROP 3 LASTPIN (-6100 3375) SIG_NAME M_A_CPU0_SB_DQ<23>
J 0
(-6090 3385);
DISPLAY 0.659574 (-6090 3385);
PAINT MONO (-6090 3385);
DISPLAY INVISIBLE (-6090 3385);
FORCEPROP 1 LASTPIN (-6100 3375) BN 23
J 0
(-6112 3383);
DISPLAY 0.489362 (-6112 3383);
PAINT GREEN (-6112 3383);
FORCEPROP 2 LAST CDS_LIB mstr_standard
J 0
(-6050 3375);
DISPLAY 0.723404 (-6050 3375);
PAINT MONO (-6050 3375);
DISPLAY INVISIBLE (-6050 3375);
FORCEPROP 1 LAST BODY_TYPE PLUMBING
J 0
(-6050 3425);
DISPLAY 0.872340 (-6050 3425);
PAINT GREEN (-6050 3425);
DISPLAY INVISIBLE (-6050 3425);
FORCEPROP 1 LAST HDL_TAP TRUE
J 0
(-5725 3250);
DISPLAY 0.872340 (-5725 3250);
DISPLAY INVISIBLE (-5725 3250);
FORCEPROP 1 LAST PATH I403
J 0
(-6052 3375);
DISPLAY 0.872340 (-6052 3375);
PAINT GREEN (-6052 3375);
DISPLAY INVISIBLE (-6052 3375);
FORCEADD TAP..1
(-6050 3225);
FORCEPROP 3 LASTPIN (-6100 3225) SIG_NAME M_A_CPU0_SB_DQ<20>
J 0
(-6090 3235);
DISPLAY 0.659574 (-6090 3235);
PAINT MONO (-6090 3235);
DISPLAY INVISIBLE (-6090 3235);
FORCEPROP 1 LASTPIN (-6100 3225) BN 20
J 0
(-6112 3233);
DISPLAY 0.489362 (-6112 3233);
PAINT GREEN (-6112 3233);
FORCEPROP 2 LAST CDS_LIB mstr_standard
J 0
(-6050 3225);
DISPLAY 0.723404 (-6050 3225);
PAINT MONO (-6050 3225);
DISPLAY INVISIBLE (-6050 3225);
FORCEPROP 1 LAST BODY_TYPE PLUMBING
J 0
(-6050 3275);
DISPLAY 0.872340 (-6050 3275);
PAINT GREEN (-6050 3275);
DISPLAY INVISIBLE (-6050 3275);
FORCEPROP 1 LAST HDL_TAP TRUE
J 0
(-5725 3100);
DISPLAY 0.872340 (-5725 3100);
DISPLAY INVISIBLE (-5725 3100);
FORCEPROP 1 LAST PATH I404
J 0
(-6052 3225);
DISPLAY 0.872340 (-6052 3225);
PAINT GREEN (-6052 3225);
DISPLAY INVISIBLE (-6052 3225);
FORCEADD TAP..1
(-6050 3275);
FORCEPROP 3 LASTPIN (-6100 3275) SIG_NAME M_A_CPU0_SB_DQ<21>
J 0
(-6090 3285);
DISPLAY 0.659574 (-6090 3285);
PAINT MONO (-6090 3285);
DISPLAY INVISIBLE (-6090 3285);
FORCEPROP 1 LASTPIN (-6100 3275) BN 21
J 0
(-6112 3283);
DISPLAY 0.489362 (-6112 3283);
PAINT GREEN (-6112 3283);
FORCEPROP 2 LAST CDS_LIB mstr_standard
J 0
(-6050 3275);
DISPLAY 0.723404 (-6050 3275);
PAINT MONO (-6050 3275);
DISPLAY INVISIBLE (-6050 3275);
FORCEPROP 1 LAST BODY_TYPE PLUMBING
J 0
(-6050 3325);
DISPLAY 0.872340 (-6050 3325);
PAINT GREEN (-6050 3325);
DISPLAY INVISIBLE (-6050 3325);
FORCEPROP 1 LAST HDL_TAP TRUE
J 0
(-5725 3150);
DISPLAY 0.872340 (-5725 3150);
DISPLAY INVISIBLE (-5725 3150);
FORCEPROP 1 LAST PATH I405
J 0
(-6052 3275);
DISPLAY 0.872340 (-6052 3275);
PAINT GREEN (-6052 3275);
DISPLAY INVISIBLE (-6052 3275);
FORCEADD TAP..1
(-6050 3325);
FORCEPROP 3 LASTPIN (-6100 3325) SIG_NAME M_A_CPU0_SB_DQ<22>
J 0
(-6090 3335);
DISPLAY 0.659574 (-6090 3335);
PAINT MONO (-6090 3335);
DISPLAY INVISIBLE (-6090 3335);
FORCEPROP 1 LASTPIN (-6100 3325) BN 22
J 0
(-6112 3333);
DISPLAY 0.489362 (-6112 3333);
PAINT GREEN (-6112 3333);
FORCEPROP 2 LAST CDS_LIB mstr_standard
J 0
(-6050 3325);
DISPLAY 0.723404 (-6050 3325);
PAINT MONO (-6050 3325);
DISPLAY INVISIBLE (-6050 3325);
FORCEPROP 1 LAST BODY_TYPE PLUMBING
J 0
(-6050 3375);
DISPLAY 0.872340 (-6050 3375);
PAINT GREEN (-6050 3375);
DISPLAY INVISIBLE (-6050 3375);
FORCEPROP 1 LAST HDL_TAP TRUE
J 0
(-5725 3200);
DISPLAY 0.872340 (-5725 3200);
DISPLAY INVISIBLE (-5725 3200);
FORCEPROP 1 LAST PATH I406
J 0
(-6052 3325);
DISPLAY 0.872340 (-6052 3325);
PAINT GREEN (-6052 3325);
DISPLAY INVISIBLE (-6052 3325);
FORCEADD TAP..1
(-6050 3425);
FORCEPROP 3 LASTPIN (-6100 3425) SIG_NAME M_A_CPU0_SB_DQ<24>
J 0
(-6090 3435);
DISPLAY 0.659574 (-6090 3435);
PAINT MONO (-6090 3435);
DISPLAY INVISIBLE (-6090 3435);
FORCEPROP 1 LASTPIN (-6100 3425) BN 24
J 0
(-6112 3433);
DISPLAY 0.489362 (-6112 3433);
PAINT GREEN (-6112 3433);
FORCEPROP 2 LAST CDS_LIB mstr_standard
J 0
(-6050 3425);
DISPLAY 0.723404 (-6050 3425);
PAINT MONO (-6050 3425);
DISPLAY INVISIBLE (-6050 3425);
FORCEPROP 1 LAST BODY_TYPE PLUMBING
J 0
(-6050 3475);
DISPLAY 0.872340 (-6050 3475);
PAINT GREEN (-6050 3475);
DISPLAY INVISIBLE (-6050 3475);
FORCEPROP 1 LAST HDL_TAP TRUE
J 0
(-5725 3300);
DISPLAY 0.872340 (-5725 3300);
DISPLAY INVISIBLE (-5725 3300);
FORCEPROP 1 LAST PATH I407
J 0
(-6052 3425);
DISPLAY 0.872340 (-6052 3425);
PAINT GREEN (-6052 3425);
DISPLAY INVISIBLE (-6052 3425);
FORCEADD TAP..1
(-6050 3625);
FORCEPROP 3 LASTPIN (-6100 3625) SIG_NAME M_A_CPU0_SB_DQ<28>
J 0
(-6090 3635);
DISPLAY 0.659574 (-6090 3635);
PAINT MONO (-6090 3635);
DISPLAY INVISIBLE (-6090 3635);
FORCEPROP 1 LASTPIN (-6100 3625) BN 28
J 0
(-6112 3633);
DISPLAY 0.489362 (-6112 3633);
PAINT GREEN (-6112 3633);
FORCEPROP 2 LAST CDS_LIB mstr_standard
J 0
(-6050 3625);
DISPLAY 0.723404 (-6050 3625);
PAINT MONO (-6050 3625);
DISPLAY INVISIBLE (-6050 3625);
FORCEPROP 1 LAST BODY_TYPE PLUMBING
J 0
(-6050 3675);
DISPLAY 0.872340 (-6050 3675);
PAINT GREEN (-6050 3675);
DISPLAY INVISIBLE (-6050 3675);
FORCEPROP 1 LAST HDL_TAP TRUE
J 0
(-5725 3500);
DISPLAY 0.872340 (-5725 3500);
DISPLAY INVISIBLE (-5725 3500);
FORCEPROP 1 LAST PATH I408
J 0
(-6052 3625);
DISPLAY 0.872340 (-6052 3625);
PAINT GREEN (-6052 3625);
DISPLAY INVISIBLE (-6052 3625);
FORCEADD TAP..1
(-6050 3475);
FORCEPROP 3 LASTPIN (-6100 3475) SIG_NAME M_A_CPU0_SB_DQ<25>
J 0
(-6090 3485);
DISPLAY 0.659574 (-6090 3485);
PAINT MONO (-6090 3485);
DISPLAY INVISIBLE (-6090 3485);
FORCEPROP 1 LASTPIN (-6100 3475) BN 25
J 0
(-6112 3483);
DISPLAY 0.489362 (-6112 3483);
PAINT GREEN (-6112 3483);
FORCEPROP 2 LAST CDS_LIB mstr_standard
J 0
(-6050 3475);
DISPLAY 0.723404 (-6050 3475);
PAINT MONO (-6050 3475);
DISPLAY INVISIBLE (-6050 3475);
FORCEPROP 1 LAST BODY_TYPE PLUMBING
J 0
(-6050 3525);
DISPLAY 0.872340 (-6050 3525);
PAINT GREEN (-6050 3525);
DISPLAY INVISIBLE (-6050 3525);
FORCEPROP 1 LAST HDL_TAP TRUE
J 0
(-5725 3350);
DISPLAY 0.872340 (-5725 3350);
DISPLAY INVISIBLE (-5725 3350);
FORCEPROP 1 LAST PATH I409
J 0
(-6052 3475);
DISPLAY 0.872340 (-6052 3475);
PAINT GREEN (-6052 3475);
DISPLAY INVISIBLE (-6052 3475);
FORCEADD TAP..1
(-6050 3525);
FORCEPROP 3 LASTPIN (-6100 3525) SIG_NAME M_A_CPU0_SB_DQ<26>
J 0
(-6090 3535);
DISPLAY 0.659574 (-6090 3535);
PAINT MONO (-6090 3535);
DISPLAY INVISIBLE (-6090 3535);
FORCEPROP 1 LASTPIN (-6100 3525) BN 26
J 0
(-6112 3533);
DISPLAY 0.489362 (-6112 3533);
PAINT GREEN (-6112 3533);
FORCEPROP 2 LAST CDS_LIB mstr_standard
J 0
(-6050 3525);
DISPLAY 0.723404 (-6050 3525);
PAINT MONO (-6050 3525);
DISPLAY INVISIBLE (-6050 3525);
FORCEPROP 1 LAST BODY_TYPE PLUMBING
J 0
(-6050 3575);
DISPLAY 0.872340 (-6050 3575);
PAINT GREEN (-6050 3575);
DISPLAY INVISIBLE (-6050 3575);
FORCEPROP 1 LAST HDL_TAP TRUE
J 0
(-5725 3400);
DISPLAY 0.872340 (-5725 3400);
DISPLAY INVISIBLE (-5725 3400);
FORCEPROP 1 LAST PATH I410
J 0
(-6052 3525);
DISPLAY 0.872340 (-6052 3525);
PAINT GREEN (-6052 3525);
DISPLAY INVISIBLE (-6052 3525);
FORCEADD TAP..1
(-6050 3575);
FORCEPROP 3 LASTPIN (-6100 3575) SIG_NAME M_A_CPU0_SB_DQ<27>
J 0
(-6090 3585);
DISPLAY 0.659574 (-6090 3585);
PAINT MONO (-6090 3585);
DISPLAY INVISIBLE (-6090 3585);
FORCEPROP 1 LASTPIN (-6100 3575) BN 27
J 0
(-6112 3583);
DISPLAY 0.489362 (-6112 3583);
PAINT GREEN (-6112 3583);
FORCEPROP 2 LAST CDS_LIB mstr_standard
J 0
(-6050 3575);
DISPLAY 0.723404 (-6050 3575);
PAINT MONO (-6050 3575);
DISPLAY INVISIBLE (-6050 3575);
FORCEPROP 1 LAST BODY_TYPE PLUMBING
J 0
(-6050 3625);
DISPLAY 0.872340 (-6050 3625);
PAINT GREEN (-6050 3625);
DISPLAY INVISIBLE (-6050 3625);
FORCEPROP 1 LAST HDL_TAP TRUE
J 0
(-5725 3450);
DISPLAY 0.872340 (-5725 3450);
DISPLAY INVISIBLE (-5725 3450);
FORCEPROP 1 LAST PATH I411
J 0
(-6052 3575);
DISPLAY 0.872340 (-6052 3575);
PAINT GREEN (-6052 3575);
DISPLAY INVISIBLE (-6052 3575);
FORCEADD TAP..1
(-6050 3675);
FORCEPROP 3 LASTPIN (-6100 3675) SIG_NAME M_A_CPU0_SB_DQ<29>
J 0
(-6090 3685);
DISPLAY 0.659574 (-6090 3685);
PAINT MONO (-6090 3685);
DISPLAY INVISIBLE (-6090 3685);
FORCEPROP 1 LASTPIN (-6100 3675) BN 29
J 0
(-6112 3683);
DISPLAY 0.489362 (-6112 3683);
PAINT GREEN (-6112 3683);
FORCEPROP 2 LAST CDS_LIB mstr_standard
J 0
(-6050 3675);
DISPLAY 0.723404 (-6050 3675);
PAINT MONO (-6050 3675);
DISPLAY INVISIBLE (-6050 3675);
FORCEPROP 1 LAST BODY_TYPE PLUMBING
J 0
(-6050 3725);
DISPLAY 0.872340 (-6050 3725);
PAINT GREEN (-6050 3725);
DISPLAY INVISIBLE (-6050 3725);
FORCEPROP 1 LAST HDL_TAP TRUE
J 0
(-5725 3550);
DISPLAY 0.872340 (-5725 3550);
DISPLAY INVISIBLE (-5725 3550);
FORCEPROP 1 LAST PATH I412
J 0
(-6052 3675);
DISPLAY 0.872340 (-6052 3675);
PAINT GREEN (-6052 3675);
DISPLAY INVISIBLE (-6052 3675);
FORCEADD TAP..1
(-6050 3875);
FORCEPROP 3 LASTPIN (-6100 3875) SIG_NAME M_A_CPU0_SA_DQ<0>
J 0
(-6090 3885);
DISPLAY 0.659574 (-6090 3885);
PAINT MONO (-6090 3885);
DISPLAY INVISIBLE (-6090 3885);
FORCEPROP 1 LASTPIN (-6100 3875) BN 0
J 0
(-6112 3883);
DISPLAY 0.489362 (-6112 3883);
PAINT GREEN (-6112 3883);
FORCEPROP 2 LAST CDS_LIB mstr_standard
J 0
(-6050 3875);
DISPLAY 0.723404 (-6050 3875);
PAINT MONO (-6050 3875);
DISPLAY INVISIBLE (-6050 3875);
FORCEPROP 1 LAST BODY_TYPE PLUMBING
J 0
(-6050 3925);
DISPLAY 0.872340 (-6050 3925);
PAINT GREEN (-6050 3925);
DISPLAY INVISIBLE (-6050 3925);
FORCEPROP 1 LAST HDL_TAP TRUE
J 0
(-5725 3750);
DISPLAY 0.872340 (-5725 3750);
DISPLAY INVISIBLE (-5725 3750);
FORCEPROP 1 LAST PATH I413
J 0
(-6052 3875);
DISPLAY 0.872340 (-6052 3875);
PAINT GREEN (-6052 3875);
DISPLAY INVISIBLE (-6052 3875);
FORCEADD TAP..1
(-6050 3725);
FORCEPROP 3 LASTPIN (-6100 3725) SIG_NAME M_A_CPU0_SB_DQ<30>
J 0
(-6090 3735);
DISPLAY 0.659574 (-6090 3735);
PAINT MONO (-6090 3735);
DISPLAY INVISIBLE (-6090 3735);
FORCEPROP 1 LASTPIN (-6100 3725) BN 30
J 0
(-6112 3733);
DISPLAY 0.489362 (-6112 3733);
PAINT GREEN (-6112 3733);
FORCEPROP 2 LAST CDS_LIB mstr_standard
J 0
(-6050 3725);
DISPLAY 0.723404 (-6050 3725);
PAINT MONO (-6050 3725);
DISPLAY INVISIBLE (-6050 3725);
FORCEPROP 1 LAST BODY_TYPE PLUMBING
J 0
(-6050 3775);
DISPLAY 0.872340 (-6050 3775);
PAINT GREEN (-6050 3775);
DISPLAY INVISIBLE (-6050 3775);
FORCEPROP 1 LAST HDL_TAP TRUE
J 0
(-5725 3600);
DISPLAY 0.872340 (-5725 3600);
DISPLAY INVISIBLE (-5725 3600);
FORCEPROP 1 LAST PATH I414
J 0
(-6052 3725);
DISPLAY 0.872340 (-6052 3725);
PAINT GREEN (-6052 3725);
DISPLAY INVISIBLE (-6052 3725);
FORCEADD TAP..1
(-6050 3775);
FORCEPROP 3 LASTPIN (-6100 3775) SIG_NAME M_A_CPU0_SB_DQ<31>
J 0
(-6090 3785);
DISPLAY 0.659574 (-6090 3785);
PAINT MONO (-6090 3785);
DISPLAY INVISIBLE (-6090 3785);
FORCEPROP 1 LASTPIN (-6100 3775) BN 31
J 0
(-6112 3783);
DISPLAY 0.489362 (-6112 3783);
PAINT GREEN (-6112 3783);
FORCEPROP 2 LAST CDS_LIB mstr_standard
J 0
(-6050 3775);
DISPLAY 0.723404 (-6050 3775);
PAINT MONO (-6050 3775);
DISPLAY INVISIBLE (-6050 3775);
FORCEPROP 1 LAST BODY_TYPE PLUMBING
J 0
(-6050 3825);
DISPLAY 0.872340 (-6050 3825);
PAINT GREEN (-6050 3825);
DISPLAY INVISIBLE (-6050 3825);
FORCEPROP 1 LAST HDL_TAP TRUE
J 0
(-5725 3650);
DISPLAY 0.872340 (-5725 3650);
DISPLAY INVISIBLE (-5725 3650);
FORCEPROP 1 LAST PATH I415
J 0
(-6052 3775);
DISPLAY 0.872340 (-6052 3775);
PAINT GREEN (-6052 3775);
DISPLAY INVISIBLE (-6052 3775);
FORCEADD TAP..1
(-6050 3975);
FORCEPROP 3 LASTPIN (-6100 3975) SIG_NAME M_A_CPU0_SA_DQ<2>
J 0
(-6090 3985);
DISPLAY 0.659574 (-6090 3985);
PAINT MONO (-6090 3985);
DISPLAY INVISIBLE (-6090 3985);
FORCEPROP 1 LASTPIN (-6100 3975) BN 2
J 0
(-6112 3983);
DISPLAY 0.489362 (-6112 3983);
PAINT GREEN (-6112 3983);
FORCEPROP 2 LAST CDS_LIB mstr_standard
J 0
(-6050 3975);
DISPLAY 0.723404 (-6050 3975);
PAINT MONO (-6050 3975);
DISPLAY INVISIBLE (-6050 3975);
FORCEPROP 1 LAST BODY_TYPE PLUMBING
J 0
(-6050 4025);
DISPLAY 0.872340 (-6050 4025);
PAINT GREEN (-6050 4025);
DISPLAY INVISIBLE (-6050 4025);
FORCEPROP 1 LAST HDL_TAP TRUE
J 0
(-5725 3850);
DISPLAY 0.872340 (-5725 3850);
DISPLAY INVISIBLE (-5725 3850);
FORCEPROP 1 LAST PATH I416
J 0
(-6052 3975);
DISPLAY 0.872340 (-6052 3975);
PAINT GREEN (-6052 3975);
DISPLAY INVISIBLE (-6052 3975);
FORCEADD TAP..1
(-6050 3925);
FORCEPROP 3 LASTPIN (-6100 3925) SIG_NAME M_A_CPU0_SA_DQ<1>
J 0
(-6090 3935);
DISPLAY 0.659574 (-6090 3935);
PAINT MONO (-6090 3935);
DISPLAY INVISIBLE (-6090 3935);
FORCEPROP 1 LASTPIN (-6100 3925) BN 1
J 0
(-6112 3933);
DISPLAY 0.489362 (-6112 3933);
PAINT GREEN (-6112 3933);
FORCEPROP 2 LAST CDS_LIB mstr_standard
J 0
(-6050 3925);
DISPLAY 0.723404 (-6050 3925);
PAINT MONO (-6050 3925);
DISPLAY INVISIBLE (-6050 3925);
FORCEPROP 1 LAST BODY_TYPE PLUMBING
J 0
(-6050 3975);
DISPLAY 0.872340 (-6050 3975);
PAINT GREEN (-6050 3975);
DISPLAY INVISIBLE (-6050 3975);
FORCEPROP 1 LAST HDL_TAP TRUE
J 0
(-5725 3800);
DISPLAY 0.872340 (-5725 3800);
DISPLAY INVISIBLE (-5725 3800);
FORCEPROP 1 LAST PATH I417
J 0
(-6052 3925);
DISPLAY 0.872340 (-6052 3925);
PAINT GREEN (-6052 3925);
DISPLAY INVISIBLE (-6052 3925);
FORCEADD TAP..1
(-6050 4025);
FORCEPROP 3 LASTPIN (-6100 4025) SIG_NAME M_A_CPU0_SA_DQ<3>
J 0
(-6090 4035);
DISPLAY 0.659574 (-6090 4035);
PAINT MONO (-6090 4035);
DISPLAY INVISIBLE (-6090 4035);
FORCEPROP 1 LASTPIN (-6100 4025) BN 3
J 0
(-6112 4033);
DISPLAY 0.489362 (-6112 4033);
PAINT GREEN (-6112 4033);
FORCEPROP 2 LAST CDS_LIB mstr_standard
J 0
(-6050 4025);
DISPLAY 0.723404 (-6050 4025);
PAINT MONO (-6050 4025);
DISPLAY INVISIBLE (-6050 4025);
FORCEPROP 1 LAST BODY_TYPE PLUMBING
J 0
(-6050 4075);
DISPLAY 0.872340 (-6050 4075);
PAINT GREEN (-6050 4075);
DISPLAY INVISIBLE (-6050 4075);
FORCEPROP 1 LAST HDL_TAP TRUE
J 0
(-5725 3900);
DISPLAY 0.872340 (-5725 3900);
DISPLAY INVISIBLE (-5725 3900);
FORCEPROP 1 LAST PATH I418
J 0
(-6052 4025);
DISPLAY 0.872340 (-6052 4025);
PAINT GREEN (-6052 4025);
DISPLAY INVISIBLE (-6052 4025);
FORCEADD TAP..1
(-6050 4125);
FORCEPROP 3 LASTPIN (-6100 4125) SIG_NAME M_A_CPU0_SA_DQ<5>
J 0
(-6090 4135);
DISPLAY 0.659574 (-6090 4135);
PAINT MONO (-6090 4135);
DISPLAY INVISIBLE (-6090 4135);
FORCEPROP 1 LASTPIN (-6100 4125) BN 5
J 0
(-6112 4133);
DISPLAY 0.489362 (-6112 4133);
PAINT GREEN (-6112 4133);
FORCEPROP 2 LAST CDS_LIB mstr_standard
J 0
(-6050 4125);
DISPLAY 0.723404 (-6050 4125);
PAINT MONO (-6050 4125);
DISPLAY INVISIBLE (-6050 4125);
FORCEPROP 1 LAST BODY_TYPE PLUMBING
J 0
(-6050 4175);
DISPLAY 0.872340 (-6050 4175);
PAINT GREEN (-6050 4175);
DISPLAY INVISIBLE (-6050 4175);
FORCEPROP 1 LAST HDL_TAP TRUE
J 0
(-5725 4000);
DISPLAY 0.872340 (-5725 4000);
DISPLAY INVISIBLE (-5725 4000);
FORCEPROP 1 LAST PATH I419
J 0
(-6052 4125);
DISPLAY 0.872340 (-6052 4125);
PAINT GREEN (-6052 4125);
DISPLAY INVISIBLE (-6052 4125);
FORCEADD TAP..1
(-6050 4075);
FORCEPROP 3 LASTPIN (-6100 4075) SIG_NAME M_A_CPU0_SA_DQ<4>
J 0
(-6090 4085);
DISPLAY 0.659574 (-6090 4085);
PAINT MONO (-6090 4085);
DISPLAY INVISIBLE (-6090 4085);
FORCEPROP 1 LASTPIN (-6100 4075) BN 4
J 0
(-6112 4083);
DISPLAY 0.489362 (-6112 4083);
PAINT GREEN (-6112 4083);
FORCEPROP 2 LAST CDS_LIB mstr_standard
J 0
(-6050 4075);
DISPLAY 0.723404 (-6050 4075);
PAINT MONO (-6050 4075);
DISPLAY INVISIBLE (-6050 4075);
FORCEPROP 1 LAST BODY_TYPE PLUMBING
J 0
(-6050 4125);
DISPLAY 0.872340 (-6050 4125);
PAINT GREEN (-6050 4125);
DISPLAY INVISIBLE (-6050 4125);
FORCEPROP 1 LAST HDL_TAP TRUE
J 0
(-5725 3950);
DISPLAY 0.872340 (-5725 3950);
DISPLAY INVISIBLE (-5725 3950);
FORCEPROP 1 LAST PATH I420
J 0
(-6052 4075);
DISPLAY 0.872340 (-6052 4075);
PAINT GREEN (-6052 4075);
DISPLAY INVISIBLE (-6052 4075);
FORCEADD TAP..1
(-6050 4225);
FORCEPROP 3 LASTPIN (-6100 4225) SIG_NAME M_A_CPU0_SA_DQ<7>
J 0
(-6090 4235);
DISPLAY 0.659574 (-6090 4235);
PAINT MONO (-6090 4235);
DISPLAY INVISIBLE (-6090 4235);
FORCEPROP 1 LASTPIN (-6100 4225) BN 7
J 0
(-6112 4233);
DISPLAY 0.489362 (-6112 4233);
PAINT GREEN (-6112 4233);
FORCEPROP 2 LAST CDS_LIB mstr_standard
J 0
(-6050 4225);
DISPLAY 0.723404 (-6050 4225);
PAINT MONO (-6050 4225);
DISPLAY INVISIBLE (-6050 4225);
FORCEPROP 1 LAST BODY_TYPE PLUMBING
J 0
(-6050 4275);
DISPLAY 0.872340 (-6050 4275);
PAINT GREEN (-6050 4275);
DISPLAY INVISIBLE (-6050 4275);
FORCEPROP 1 LAST HDL_TAP TRUE
J 0
(-5725 4100);
DISPLAY 0.872340 (-5725 4100);
DISPLAY INVISIBLE (-5725 4100);
FORCEPROP 1 LAST PATH I421
J 0
(-6052 4225);
DISPLAY 0.872340 (-6052 4225);
PAINT GREEN (-6052 4225);
DISPLAY INVISIBLE (-6052 4225);
FORCEADD TAP..1
(-6050 4175);
FORCEPROP 3 LASTPIN (-6100 4175) SIG_NAME M_A_CPU0_SA_DQ<6>
J 0
(-6090 4185);
DISPLAY 0.659574 (-6090 4185);
PAINT MONO (-6090 4185);
DISPLAY INVISIBLE (-6090 4185);
FORCEPROP 1 LASTPIN (-6100 4175) BN 6
J 0
(-6112 4183);
DISPLAY 0.489362 (-6112 4183);
PAINT GREEN (-6112 4183);
FORCEPROP 2 LAST CDS_LIB mstr_standard
J 0
(-6050 4175);
DISPLAY 0.723404 (-6050 4175);
PAINT MONO (-6050 4175);
DISPLAY INVISIBLE (-6050 4175);
FORCEPROP 1 LAST BODY_TYPE PLUMBING
J 0
(-6050 4225);
DISPLAY 0.872340 (-6050 4225);
PAINT GREEN (-6050 4225);
DISPLAY INVISIBLE (-6050 4225);
FORCEPROP 1 LAST HDL_TAP TRUE
J 0
(-5725 4050);
DISPLAY 0.872340 (-5725 4050);
DISPLAY INVISIBLE (-5725 4050);
FORCEPROP 1 LAST PATH I422
J 0
(-6052 4175);
DISPLAY 0.872340 (-6052 4175);
PAINT GREEN (-6052 4175);
DISPLAY INVISIBLE (-6052 4175);
FORCEADD TAP..1
(-6050 4275);
FORCEPROP 3 LASTPIN (-6100 4275) SIG_NAME M_A_CPU0_SA_DQ<8>
J 0
(-6090 4285);
DISPLAY 0.659574 (-6090 4285);
PAINT MONO (-6090 4285);
DISPLAY INVISIBLE (-6090 4285);
FORCEPROP 1 LASTPIN (-6100 4275) BN 8
J 0
(-6112 4283);
DISPLAY 0.489362 (-6112 4283);
PAINT GREEN (-6112 4283);
FORCEPROP 2 LAST CDS_LIB mstr_standard
J 0
(-6050 4275);
DISPLAY 0.723404 (-6050 4275);
PAINT MONO (-6050 4275);
DISPLAY INVISIBLE (-6050 4275);
FORCEPROP 1 LAST BODY_TYPE PLUMBING
J 0
(-6050 4325);
DISPLAY 0.872340 (-6050 4325);
PAINT GREEN (-6050 4325);
DISPLAY INVISIBLE (-6050 4325);
FORCEPROP 1 LAST HDL_TAP TRUE
J 0
(-5725 4150);
DISPLAY 0.872340 (-5725 4150);
DISPLAY INVISIBLE (-5725 4150);
FORCEPROP 1 LAST PATH I423
J 0
(-6052 4275);
DISPLAY 0.872340 (-6052 4275);
PAINT GREEN (-6052 4275);
DISPLAY INVISIBLE (-6052 4275);
FORCEADD TAP..1
(-6050 4375);
FORCEPROP 3 LASTPIN (-6100 4375) SIG_NAME M_A_CPU0_SA_DQ<10>
J 0
(-6090 4385);
DISPLAY 0.659574 (-6090 4385);
PAINT MONO (-6090 4385);
DISPLAY INVISIBLE (-6090 4385);
FORCEPROP 1 LASTPIN (-6100 4375) BN 10
J 0
(-6112 4383);
DISPLAY 0.489362 (-6112 4383);
PAINT GREEN (-6112 4383);
FORCEPROP 2 LAST CDS_LIB mstr_standard
J 0
(-6050 4375);
DISPLAY 0.723404 (-6050 4375);
PAINT MONO (-6050 4375);
DISPLAY INVISIBLE (-6050 4375);
FORCEPROP 1 LAST BODY_TYPE PLUMBING
J 0
(-6050 4425);
DISPLAY 0.872340 (-6050 4425);
PAINT GREEN (-6050 4425);
DISPLAY INVISIBLE (-6050 4425);
FORCEPROP 1 LAST HDL_TAP TRUE
J 0
(-5725 4250);
DISPLAY 0.872340 (-5725 4250);
DISPLAY INVISIBLE (-5725 4250);
FORCEPROP 1 LAST PATH I424
J 0
(-6052 4375);
DISPLAY 0.872340 (-6052 4375);
PAINT GREEN (-6052 4375);
DISPLAY INVISIBLE (-6052 4375);
FORCEADD TAP..1
(-6050 4325);
FORCEPROP 3 LASTPIN (-6100 4325) SIG_NAME M_A_CPU0_SA_DQ<9>
J 0
(-6090 4335);
DISPLAY 0.659574 (-6090 4335);
PAINT MONO (-6090 4335);
DISPLAY INVISIBLE (-6090 4335);
FORCEPROP 1 LASTPIN (-6100 4325) BN 9
J 0
(-6112 4333);
DISPLAY 0.489362 (-6112 4333);
PAINT GREEN (-6112 4333);
FORCEPROP 2 LAST CDS_LIB mstr_standard
J 0
(-6050 4325);
DISPLAY 0.723404 (-6050 4325);
PAINT MONO (-6050 4325);
DISPLAY INVISIBLE (-6050 4325);
FORCEPROP 1 LAST BODY_TYPE PLUMBING
J 0
(-6050 4375);
DISPLAY 0.872340 (-6050 4375);
PAINT GREEN (-6050 4375);
DISPLAY INVISIBLE (-6050 4375);
FORCEPROP 1 LAST HDL_TAP TRUE
J 0
(-5725 4200);
DISPLAY 0.872340 (-5725 4200);
DISPLAY INVISIBLE (-5725 4200);
FORCEPROP 1 LAST PATH I425
J 0
(-6052 4325);
DISPLAY 0.872340 (-6052 4325);
PAINT GREEN (-6052 4325);
DISPLAY INVISIBLE (-6052 4325);
FORCEADD TAP..1
(-6050 4425);
FORCEPROP 3 LASTPIN (-6100 4425) SIG_NAME M_A_CPU0_SA_DQ<11>
J 0
(-6090 4435);
DISPLAY 0.659574 (-6090 4435);
PAINT MONO (-6090 4435);
DISPLAY INVISIBLE (-6090 4435);
FORCEPROP 1 LASTPIN (-6100 4425) BN 11
J 0
(-6112 4433);
DISPLAY 0.489362 (-6112 4433);
PAINT GREEN (-6112 4433);
FORCEPROP 2 LAST CDS_LIB mstr_standard
J 0
(-6050 4425);
DISPLAY 0.723404 (-6050 4425);
PAINT MONO (-6050 4425);
DISPLAY INVISIBLE (-6050 4425);
FORCEPROP 1 LAST BODY_TYPE PLUMBING
J 0
(-6050 4475);
DISPLAY 0.872340 (-6050 4475);
PAINT GREEN (-6050 4475);
DISPLAY INVISIBLE (-6050 4475);
FORCEPROP 1 LAST HDL_TAP TRUE
J 0
(-5725 4300);
DISPLAY 0.872340 (-5725 4300);
DISPLAY INVISIBLE (-5725 4300);
FORCEPROP 1 LAST PATH I426
J 0
(-6052 4425);
DISPLAY 0.872340 (-6052 4425);
PAINT GREEN (-6052 4425);
DISPLAY INVISIBLE (-6052 4425);
FORCEADD TAP..1
(-6050 4475);
FORCEPROP 3 LASTPIN (-6100 4475) SIG_NAME M_A_CPU0_SA_DQ<12>
J 0
(-6090 4485);
DISPLAY 0.659574 (-6090 4485);
PAINT MONO (-6090 4485);
DISPLAY INVISIBLE (-6090 4485);
FORCEPROP 1 LASTPIN (-6100 4475) BN 12
J 0
(-6112 4483);
DISPLAY 0.489362 (-6112 4483);
PAINT GREEN (-6112 4483);
FORCEPROP 2 LAST CDS_LIB mstr_standard
J 0
(-6050 4475);
DISPLAY 0.723404 (-6050 4475);
PAINT MONO (-6050 4475);
DISPLAY INVISIBLE (-6050 4475);
FORCEPROP 1 LAST BODY_TYPE PLUMBING
J 0
(-6050 4525);
DISPLAY 0.872340 (-6050 4525);
PAINT GREEN (-6050 4525);
DISPLAY INVISIBLE (-6050 4525);
FORCEPROP 1 LAST HDL_TAP TRUE
J 0
(-5725 4350);
DISPLAY 0.872340 (-5725 4350);
DISPLAY INVISIBLE (-5725 4350);
FORCEPROP 1 LAST PATH I427
J 0
(-6052 4475);
DISPLAY 0.872340 (-6052 4475);
PAINT GREEN (-6052 4475);
DISPLAY INVISIBLE (-6052 4475);
FORCEADD TAP..1
(-6050 4525);
FORCEPROP 3 LASTPIN (-6100 4525) SIG_NAME M_A_CPU0_SA_DQ<13>
J 0
(-6090 4535);
DISPLAY 0.659574 (-6090 4535);
PAINT MONO (-6090 4535);
DISPLAY INVISIBLE (-6090 4535);
FORCEPROP 1 LASTPIN (-6100 4525) BN 13
J 0
(-6112 4533);
DISPLAY 0.489362 (-6112 4533);
PAINT GREEN (-6112 4533);
FORCEPROP 2 LAST CDS_LIB mstr_standard
J 0
(-6050 4525);
DISPLAY 0.723404 (-6050 4525);
PAINT MONO (-6050 4525);
DISPLAY INVISIBLE (-6050 4525);
FORCEPROP 1 LAST BODY_TYPE PLUMBING
J 0
(-6050 4575);
DISPLAY 0.872340 (-6050 4575);
PAINT GREEN (-6050 4575);
DISPLAY INVISIBLE (-6050 4575);
FORCEPROP 1 LAST HDL_TAP TRUE
J 0
(-5725 4400);
DISPLAY 0.872340 (-5725 4400);
DISPLAY INVISIBLE (-5725 4400);
FORCEPROP 1 LAST PATH I428
J 0
(-6052 4525);
DISPLAY 0.872340 (-6052 4525);
PAINT GREEN (-6052 4525);
DISPLAY INVISIBLE (-6052 4525);
FORCEADD TAP..1
(-6050 4575);
FORCEPROP 3 LASTPIN (-6100 4575) SIG_NAME M_A_CPU0_SA_DQ<14>
J 0
(-6090 4585);
DISPLAY 0.659574 (-6090 4585);
PAINT MONO (-6090 4585);
DISPLAY INVISIBLE (-6090 4585);
FORCEPROP 1 LASTPIN (-6100 4575) BN 14
J 0
(-6112 4583);
DISPLAY 0.489362 (-6112 4583);
PAINT GREEN (-6112 4583);
FORCEPROP 2 LAST CDS_LIB mstr_standard
J 0
(-6050 4575);
DISPLAY 0.723404 (-6050 4575);
PAINT MONO (-6050 4575);
DISPLAY INVISIBLE (-6050 4575);
FORCEPROP 1 LAST BODY_TYPE PLUMBING
J 0
(-6050 4625);
DISPLAY 0.872340 (-6050 4625);
PAINT GREEN (-6050 4625);
DISPLAY INVISIBLE (-6050 4625);
FORCEPROP 1 LAST HDL_TAP TRUE
J 0
(-5725 4450);
DISPLAY 0.872340 (-5725 4450);
DISPLAY INVISIBLE (-5725 4450);
FORCEPROP 1 LAST PATH I429
J 0
(-6052 4575);
DISPLAY 0.872340 (-6052 4575);
PAINT GREEN (-6052 4575);
DISPLAY INVISIBLE (-6052 4575);
FORCEADD TAP..1
(-6050 4625);
FORCEPROP 3 LASTPIN (-6100 4625) SIG_NAME M_A_CPU0_SA_DQ<15>
J 0
(-6090 4635);
DISPLAY 0.659574 (-6090 4635);
PAINT MONO (-6090 4635);
DISPLAY INVISIBLE (-6090 4635);
FORCEPROP 1 LASTPIN (-6100 4625) BN 15
J 0
(-6112 4633);
DISPLAY 0.489362 (-6112 4633);
PAINT GREEN (-6112 4633);
FORCEPROP 2 LAST CDS_LIB mstr_standard
J 0
(-6050 4625);
DISPLAY 0.723404 (-6050 4625);
PAINT MONO (-6050 4625);
DISPLAY INVISIBLE (-6050 4625);
FORCEPROP 1 LAST BODY_TYPE PLUMBING
J 0
(-6050 4675);
DISPLAY 0.872340 (-6050 4675);
PAINT GREEN (-6050 4675);
DISPLAY INVISIBLE (-6050 4675);
FORCEPROP 1 LAST HDL_TAP TRUE
J 0
(-5725 4500);
DISPLAY 0.872340 (-5725 4500);
DISPLAY INVISIBLE (-5725 4500);
FORCEPROP 1 LAST PATH I430
J 0
(-6052 4625);
DISPLAY 0.872340 (-6052 4625);
PAINT GREEN (-6052 4625);
DISPLAY INVISIBLE (-6052 4625);
FORCEADD TAP..1
(-6050 4825);
FORCEPROP 3 LASTPIN (-6100 4825) SIG_NAME M_A_CPU0_SA_DQ<19>
J 0
(-6090 4835);
DISPLAY 0.659574 (-6090 4835);
PAINT MONO (-6090 4835);
DISPLAY INVISIBLE (-6090 4835);
FORCEPROP 1 LASTPIN (-6100 4825) BN 19
J 0
(-6112 4833);
DISPLAY 0.489362 (-6112 4833);
PAINT GREEN (-6112 4833);
FORCEPROP 2 LAST CDS_LIB mstr_standard
J 0
(-6050 4825);
DISPLAY 0.723404 (-6050 4825);
PAINT MONO (-6050 4825);
DISPLAY INVISIBLE (-6050 4825);
FORCEPROP 1 LAST BODY_TYPE PLUMBING
J 0
(-6050 4875);
DISPLAY 0.872340 (-6050 4875);
PAINT GREEN (-6050 4875);
DISPLAY INVISIBLE (-6050 4875);
FORCEPROP 1 LAST HDL_TAP TRUE
J 0
(-5725 4700);
DISPLAY 0.872340 (-5725 4700);
DISPLAY INVISIBLE (-5725 4700);
FORCEPROP 1 LAST PATH I431
J 0
(-6052 4825);
DISPLAY 0.872340 (-6052 4825);
PAINT GREEN (-6052 4825);
DISPLAY INVISIBLE (-6052 4825);
FORCEADD TAP..1
(-6050 4875);
FORCEPROP 3 LASTPIN (-6100 4875) SIG_NAME M_A_CPU0_SA_DQ<20>
J 0
(-6090 4885);
DISPLAY 0.659574 (-6090 4885);
PAINT MONO (-6090 4885);
DISPLAY INVISIBLE (-6090 4885);
FORCEPROP 1 LASTPIN (-6100 4875) BN 20
J 0
(-6112 4883);
DISPLAY 0.489362 (-6112 4883);
PAINT GREEN (-6112 4883);
FORCEPROP 2 LAST CDS_LIB mstr_standard
J 0
(-6050 4875);
DISPLAY 0.723404 (-6050 4875);
PAINT MONO (-6050 4875);
DISPLAY INVISIBLE (-6050 4875);
FORCEPROP 1 LAST BODY_TYPE PLUMBING
J 0
(-6050 4925);
DISPLAY 0.872340 (-6050 4925);
PAINT GREEN (-6050 4925);
DISPLAY INVISIBLE (-6050 4925);
FORCEPROP 1 LAST HDL_TAP TRUE
J 0
(-5725 4750);
DISPLAY 0.872340 (-5725 4750);
DISPLAY INVISIBLE (-5725 4750);
FORCEPROP 1 LAST PATH I432
J 0
(-6052 4875);
DISPLAY 0.872340 (-6052 4875);
PAINT GREEN (-6052 4875);
DISPLAY INVISIBLE (-6052 4875);
FORCEADD TAP..1
(-6050 4675);
FORCEPROP 3 LASTPIN (-6100 4675) SIG_NAME M_A_CPU0_SA_DQ<16>
J 0
(-6090 4685);
DISPLAY 0.659574 (-6090 4685);
PAINT MONO (-6090 4685);
DISPLAY INVISIBLE (-6090 4685);
FORCEPROP 1 LASTPIN (-6100 4675) BN 16
J 0
(-6112 4683);
DISPLAY 0.489362 (-6112 4683);
PAINT GREEN (-6112 4683);
FORCEPROP 2 LAST CDS_LIB mstr_standard
J 0
(-6050 4675);
DISPLAY 0.723404 (-6050 4675);
PAINT MONO (-6050 4675);
DISPLAY INVISIBLE (-6050 4675);
FORCEPROP 1 LAST BODY_TYPE PLUMBING
J 0
(-6050 4725);
DISPLAY 0.872340 (-6050 4725);
PAINT GREEN (-6050 4725);
DISPLAY INVISIBLE (-6050 4725);
FORCEPROP 1 LAST HDL_TAP TRUE
J 0
(-5725 4550);
DISPLAY 0.872340 (-5725 4550);
DISPLAY INVISIBLE (-5725 4550);
FORCEPROP 1 LAST PATH I433
J 0
(-6052 4675);
DISPLAY 0.872340 (-6052 4675);
PAINT GREEN (-6052 4675);
DISPLAY INVISIBLE (-6052 4675);
FORCEADD TAP..1
(-6050 4725);
FORCEPROP 3 LASTPIN (-6100 4725) SIG_NAME M_A_CPU0_SA_DQ<17>
J 0
(-6090 4735);
DISPLAY 0.659574 (-6090 4735);
PAINT MONO (-6090 4735);
DISPLAY INVISIBLE (-6090 4735);
FORCEPROP 1 LASTPIN (-6100 4725) BN 17
J 0
(-6112 4733);
DISPLAY 0.489362 (-6112 4733);
PAINT GREEN (-6112 4733);
FORCEPROP 2 LAST CDS_LIB mstr_standard
J 0
(-6050 4725);
DISPLAY 0.723404 (-6050 4725);
PAINT MONO (-6050 4725);
DISPLAY INVISIBLE (-6050 4725);
FORCEPROP 1 LAST BODY_TYPE PLUMBING
J 0
(-6050 4775);
DISPLAY 0.872340 (-6050 4775);
PAINT GREEN (-6050 4775);
DISPLAY INVISIBLE (-6050 4775);
FORCEPROP 1 LAST HDL_TAP TRUE
J 0
(-5725 4600);
DISPLAY 0.872340 (-5725 4600);
DISPLAY INVISIBLE (-5725 4600);
FORCEPROP 1 LAST PATH I434
J 0
(-6052 4725);
DISPLAY 0.872340 (-6052 4725);
PAINT GREEN (-6052 4725);
DISPLAY INVISIBLE (-6052 4725);
FORCEADD TAP..1
(-6050 4775);
FORCEPROP 3 LASTPIN (-6100 4775) SIG_NAME M_A_CPU0_SA_DQ<18>
J 0
(-6090 4785);
DISPLAY 0.659574 (-6090 4785);
PAINT MONO (-6090 4785);
DISPLAY INVISIBLE (-6090 4785);
FORCEPROP 1 LASTPIN (-6100 4775) BN 18
J 0
(-6112 4783);
DISPLAY 0.489362 (-6112 4783);
PAINT GREEN (-6112 4783);
FORCEPROP 2 LAST CDS_LIB mstr_standard
J 0
(-6050 4775);
DISPLAY 0.723404 (-6050 4775);
PAINT MONO (-6050 4775);
DISPLAY INVISIBLE (-6050 4775);
FORCEPROP 1 LAST BODY_TYPE PLUMBING
J 0
(-6050 4825);
DISPLAY 0.872340 (-6050 4825);
PAINT GREEN (-6050 4825);
DISPLAY INVISIBLE (-6050 4825);
FORCEPROP 1 LAST HDL_TAP TRUE
J 0
(-5725 4650);
DISPLAY 0.872340 (-5725 4650);
DISPLAY INVISIBLE (-5725 4650);
FORCEPROP 1 LAST PATH I435
J 0
(-6052 4775);
DISPLAY 0.872340 (-6052 4775);
PAINT GREEN (-6052 4775);
DISPLAY INVISIBLE (-6052 4775);
FORCEADD OFFPAGE..3
(-5500 3825);
FORCEPROP 2 LAST $XR0 10 
J 0
(-5286 3825);
DISPLAY 0.638298 (-5286 3825);
PAINT MONO (-5286 3825);
FORCEPROP 2 LAST CDS_LIB mstr_standard
J 0
(-5500 3825);
DISPLAY 0.723404 (-5500 3825);
PAINT MONO (-5500 3825);
DISPLAY INVISIBLE (-5500 3825);
FORCEPROP 1 LAST OFFPAGE TRUE
J 0
(-5175 3700);
DISPLAY 0.872340 (-5175 3700);
PAINT GREEN (-5175 3700);
DISPLAY INVISIBLE (-5175 3700);
FORCEPROP 1 LAST COMMENT_BODY TRUE
J 0
(-5550 3725);
DISPLAY 0.872340 (-5550 3725);
PAINT GREEN (-5550 3725);
DISPLAY INVISIBLE (-5550 3725);
FORCEPROP 2 LAST PATH I436
J 0
(-5175 3875);
DISPLAY 0.808511 (-5175 3875);
DISPLAY INVISIBLE (-5175 3875);
FORCEADD TAP..1
(-6050 5025);
FORCEPROP 3 LASTPIN (-6100 5025) SIG_NAME M_A_CPU0_SA_DQ<23>
J 0
(-6090 5035);
DISPLAY 0.659574 (-6090 5035);
PAINT MONO (-6090 5035);
DISPLAY INVISIBLE (-6090 5035);
FORCEPROP 1 LASTPIN (-6100 5025) BN 23
J 0
(-6112 5033);
DISPLAY 0.489362 (-6112 5033);
PAINT GREEN (-6112 5033);
FORCEPROP 2 LAST CDS_LIB mstr_standard
J 0
(-6050 5025);
DISPLAY 0.723404 (-6050 5025);
PAINT MONO (-6050 5025);
DISPLAY INVISIBLE (-6050 5025);
FORCEPROP 1 LAST BODY_TYPE PLUMBING
J 0
(-6050 5075);
DISPLAY 0.872340 (-6050 5075);
PAINT GREEN (-6050 5075);
DISPLAY INVISIBLE (-6050 5075);
FORCEPROP 1 LAST HDL_TAP TRUE
J 0
(-5725 4900);
DISPLAY 0.872340 (-5725 4900);
DISPLAY INVISIBLE (-5725 4900);
FORCEPROP 1 LAST PATH I437
J 0
(-6052 5025);
DISPLAY 0.872340 (-6052 5025);
PAINT GREEN (-6052 5025);
DISPLAY INVISIBLE (-6052 5025);
FORCEADD TAP..1
(-6050 4925);
FORCEPROP 3 LASTPIN (-6100 4925) SIG_NAME M_A_CPU0_SA_DQ<21>
J 0
(-6090 4935);
DISPLAY 0.659574 (-6090 4935);
PAINT MONO (-6090 4935);
DISPLAY INVISIBLE (-6090 4935);
FORCEPROP 1 LASTPIN (-6100 4925) BN 21
J 0
(-6112 4933);
DISPLAY 0.489362 (-6112 4933);
PAINT GREEN (-6112 4933);
FORCEPROP 2 LAST CDS_LIB mstr_standard
J 0
(-6050 4925);
DISPLAY 0.723404 (-6050 4925);
PAINT MONO (-6050 4925);
DISPLAY INVISIBLE (-6050 4925);
FORCEPROP 1 LAST BODY_TYPE PLUMBING
J 0
(-6050 4975);
DISPLAY 0.872340 (-6050 4975);
PAINT GREEN (-6050 4975);
DISPLAY INVISIBLE (-6050 4975);
FORCEPROP 1 LAST HDL_TAP TRUE
J 0
(-5725 4800);
DISPLAY 0.872340 (-5725 4800);
DISPLAY INVISIBLE (-5725 4800);
FORCEPROP 1 LAST PATH I438
J 0
(-6052 4925);
DISPLAY 0.872340 (-6052 4925);
PAINT GREEN (-6052 4925);
DISPLAY INVISIBLE (-6052 4925);
FORCEADD TAP..1
(-6050 4975);
FORCEPROP 3 LASTPIN (-6100 4975) SIG_NAME M_A_CPU0_SA_DQ<22>
J 0
(-6090 4985);
DISPLAY 0.659574 (-6090 4985);
PAINT MONO (-6090 4985);
DISPLAY INVISIBLE (-6090 4985);
FORCEPROP 1 LASTPIN (-6100 4975) BN 22
J 0
(-6112 4983);
DISPLAY 0.489362 (-6112 4983);
PAINT GREEN (-6112 4983);
FORCEPROP 2 LAST CDS_LIB mstr_standard
J 0
(-6050 4975);
DISPLAY 0.723404 (-6050 4975);
PAINT MONO (-6050 4975);
DISPLAY INVISIBLE (-6050 4975);
FORCEPROP 1 LAST BODY_TYPE PLUMBING
J 0
(-6050 5025);
DISPLAY 0.872340 (-6050 5025);
PAINT GREEN (-6050 5025);
DISPLAY INVISIBLE (-6050 5025);
FORCEPROP 1 LAST HDL_TAP TRUE
J 0
(-5725 4850);
DISPLAY 0.872340 (-5725 4850);
DISPLAY INVISIBLE (-5725 4850);
FORCEPROP 1 LAST PATH I439
J 0
(-6052 4975);
DISPLAY 0.872340 (-6052 4975);
PAINT GREEN (-6052 4975);
DISPLAY INVISIBLE (-6052 4975);
FORCEADD TAP..1
(-6050 5175);
FORCEPROP 3 LASTPIN (-6100 5175) SIG_NAME M_A_CPU0_SA_DQ<26>
J 0
(-6090 5185);
DISPLAY 0.659574 (-6090 5185);
PAINT MONO (-6090 5185);
DISPLAY INVISIBLE (-6090 5185);
FORCEPROP 1 LASTPIN (-6100 5175) BN 26
J 0
(-6112 5183);
DISPLAY 0.489362 (-6112 5183);
PAINT GREEN (-6112 5183);
FORCEPROP 2 LAST CDS_LIB mstr_standard
J 0
(-6050 5175);
DISPLAY 0.723404 (-6050 5175);
PAINT MONO (-6050 5175);
DISPLAY INVISIBLE (-6050 5175);
FORCEPROP 1 LAST BODY_TYPE PLUMBING
J 0
(-6050 5225);
DISPLAY 0.872340 (-6050 5225);
PAINT GREEN (-6050 5225);
DISPLAY INVISIBLE (-6050 5225);
FORCEPROP 1 LAST HDL_TAP TRUE
J 0
(-5725 5050);
DISPLAY 0.872340 (-5725 5050);
DISPLAY INVISIBLE (-5725 5050);
FORCEPROP 1 LAST PATH I440
J 0
(-6052 5175);
DISPLAY 0.872340 (-6052 5175);
PAINT GREEN (-6052 5175);
DISPLAY INVISIBLE (-6052 5175);
FORCEADD TAP..1
(-6050 5125);
FORCEPROP 3 LASTPIN (-6100 5125) SIG_NAME M_A_CPU0_SA_DQ<25>
J 0
(-6090 5135);
DISPLAY 0.659574 (-6090 5135);
PAINT MONO (-6090 5135);
DISPLAY INVISIBLE (-6090 5135);
FORCEPROP 1 LASTPIN (-6100 5125) BN 25
J 0
(-6112 5133);
DISPLAY 0.489362 (-6112 5133);
PAINT GREEN (-6112 5133);
FORCEPROP 2 LAST CDS_LIB mstr_standard
J 0
(-6050 5125);
DISPLAY 0.723404 (-6050 5125);
PAINT MONO (-6050 5125);
DISPLAY INVISIBLE (-6050 5125);
FORCEPROP 1 LAST BODY_TYPE PLUMBING
J 0
(-6050 5175);
DISPLAY 0.872340 (-6050 5175);
PAINT GREEN (-6050 5175);
DISPLAY INVISIBLE (-6050 5175);
FORCEPROP 1 LAST HDL_TAP TRUE
J 0
(-5725 5000);
DISPLAY 0.872340 (-5725 5000);
DISPLAY INVISIBLE (-5725 5000);
FORCEPROP 1 LAST PATH I441
J 0
(-6052 5125);
DISPLAY 0.872340 (-6052 5125);
PAINT GREEN (-6052 5125);
DISPLAY INVISIBLE (-6052 5125);
FORCEADD TAP..1
(-6050 5075);
FORCEPROP 3 LASTPIN (-6100 5075) SIG_NAME M_A_CPU0_SA_DQ<24>
J 0
(-6090 5085);
DISPLAY 0.659574 (-6090 5085);
PAINT MONO (-6090 5085);
DISPLAY INVISIBLE (-6090 5085);
FORCEPROP 1 LASTPIN (-6100 5075) BN 24
J 0
(-6112 5083);
DISPLAY 0.489362 (-6112 5083);
PAINT GREEN (-6112 5083);
FORCEPROP 2 LAST CDS_LIB mstr_standard
J 0
(-6050 5075);
DISPLAY 0.723404 (-6050 5075);
PAINT MONO (-6050 5075);
DISPLAY INVISIBLE (-6050 5075);
FORCEPROP 1 LAST BODY_TYPE PLUMBING
J 0
(-6050 5125);
DISPLAY 0.872340 (-6050 5125);
PAINT GREEN (-6050 5125);
DISPLAY INVISIBLE (-6050 5125);
FORCEPROP 1 LAST HDL_TAP TRUE
J 0
(-5725 4950);
DISPLAY 0.872340 (-5725 4950);
DISPLAY INVISIBLE (-5725 4950);
FORCEPROP 1 LAST PATH I442
J 0
(-6052 5075);
DISPLAY 0.872340 (-6052 5075);
PAINT GREEN (-6052 5075);
DISPLAY INVISIBLE (-6052 5075);
FORCEADD TAP..1
(-6050 5325);
FORCEPROP 3 LASTPIN (-6100 5325) SIG_NAME M_A_CPU0_SA_DQ<29>
J 0
(-6090 5335);
DISPLAY 0.659574 (-6090 5335);
PAINT MONO (-6090 5335);
DISPLAY INVISIBLE (-6090 5335);
FORCEPROP 1 LASTPIN (-6100 5325) BN 29
J 0
(-6112 5333);
DISPLAY 0.489362 (-6112 5333);
PAINT GREEN (-6112 5333);
FORCEPROP 2 LAST CDS_LIB mstr_standard
J 0
(-6050 5325);
DISPLAY 0.723404 (-6050 5325);
PAINT MONO (-6050 5325);
DISPLAY INVISIBLE (-6050 5325);
FORCEPROP 1 LAST BODY_TYPE PLUMBING
J 0
(-6050 5375);
DISPLAY 0.872340 (-6050 5375);
PAINT GREEN (-6050 5375);
DISPLAY INVISIBLE (-6050 5375);
FORCEPROP 1 LAST HDL_TAP TRUE
J 0
(-5725 5200);
DISPLAY 0.872340 (-5725 5200);
DISPLAY INVISIBLE (-5725 5200);
FORCEPROP 1 LAST PATH I443
J 0
(-6052 5325);
DISPLAY 0.872340 (-6052 5325);
PAINT GREEN (-6052 5325);
DISPLAY INVISIBLE (-6052 5325);
FORCEADD TAP..1
(-6050 5375);
FORCEPROP 3 LASTPIN (-6100 5375) SIG_NAME M_A_CPU0_SA_DQ<30>
J 0
(-6090 5385);
DISPLAY 0.659574 (-6090 5385);
PAINT MONO (-6090 5385);
DISPLAY INVISIBLE (-6090 5385);
FORCEPROP 1 LASTPIN (-6100 5375) BN 30
J 0
(-6112 5383);
DISPLAY 0.489362 (-6112 5383);
PAINT GREEN (-6112 5383);
FORCEPROP 2 LAST CDS_LIB mstr_standard
J 0
(-6050 5375);
DISPLAY 0.723404 (-6050 5375);
PAINT MONO (-6050 5375);
DISPLAY INVISIBLE (-6050 5375);
FORCEPROP 1 LAST BODY_TYPE PLUMBING
J 0
(-6050 5425);
DISPLAY 0.872340 (-6050 5425);
PAINT GREEN (-6050 5425);
DISPLAY INVISIBLE (-6050 5425);
FORCEPROP 1 LAST HDL_TAP TRUE
J 0
(-5725 5250);
DISPLAY 0.872340 (-5725 5250);
DISPLAY INVISIBLE (-5725 5250);
FORCEPROP 1 LAST PATH I444
J 0
(-6052 5375);
DISPLAY 0.872340 (-6052 5375);
PAINT GREEN (-6052 5375);
DISPLAY INVISIBLE (-6052 5375);
FORCEADD TAP..1
(-6050 5425);
FORCEPROP 3 LASTPIN (-6100 5425) SIG_NAME M_A_CPU0_SA_DQ<31>
J 0
(-6090 5435);
DISPLAY 0.659574 (-6090 5435);
PAINT MONO (-6090 5435);
DISPLAY INVISIBLE (-6090 5435);
FORCEPROP 1 LASTPIN (-6100 5425) BN 31
J 0
(-6112 5433);
DISPLAY 0.489362 (-6112 5433);
PAINT GREEN (-6112 5433);
FORCEPROP 2 LAST CDS_LIB mstr_standard
J 0
(-6050 5425);
DISPLAY 0.723404 (-6050 5425);
PAINT MONO (-6050 5425);
DISPLAY INVISIBLE (-6050 5425);
FORCEPROP 1 LAST BODY_TYPE PLUMBING
J 0
(-6050 5475);
DISPLAY 0.872340 (-6050 5475);
PAINT GREEN (-6050 5475);
DISPLAY INVISIBLE (-6050 5475);
FORCEPROP 1 LAST HDL_TAP TRUE
J 0
(-5725 5300);
DISPLAY 0.872340 (-5725 5300);
DISPLAY INVISIBLE (-5725 5300);
FORCEPROP 1 LAST PATH I445
J 0
(-6052 5425);
DISPLAY 0.872340 (-6052 5425);
PAINT GREEN (-6052 5425);
DISPLAY INVISIBLE (-6052 5425);
FORCEADD TAP..1
(-6050 5225);
FORCEPROP 3 LASTPIN (-6100 5225) SIG_NAME M_A_CPU0_SA_DQ<27>
J 0
(-6090 5235);
DISPLAY 0.659574 (-6090 5235);
PAINT MONO (-6090 5235);
DISPLAY INVISIBLE (-6090 5235);
FORCEPROP 1 LASTPIN (-6100 5225) BN 27
J 0
(-6112 5233);
DISPLAY 0.489362 (-6112 5233);
PAINT GREEN (-6112 5233);
FORCEPROP 2 LAST CDS_LIB mstr_standard
J 0
(-6050 5225);
DISPLAY 0.723404 (-6050 5225);
PAINT MONO (-6050 5225);
DISPLAY INVISIBLE (-6050 5225);
FORCEPROP 1 LAST BODY_TYPE PLUMBING
J 0
(-6050 5275);
DISPLAY 0.872340 (-6050 5275);
PAINT GREEN (-6050 5275);
DISPLAY INVISIBLE (-6050 5275);
FORCEPROP 1 LAST HDL_TAP TRUE
J 0
(-5725 5100);
DISPLAY 0.872340 (-5725 5100);
DISPLAY INVISIBLE (-5725 5100);
FORCEPROP 1 LAST PATH I446
J 0
(-6052 5225);
DISPLAY 0.872340 (-6052 5225);
PAINT GREEN (-6052 5225);
DISPLAY INVISIBLE (-6052 5225);
FORCEADD TAP..1
(-6050 5275);
FORCEPROP 3 LASTPIN (-6100 5275) SIG_NAME M_A_CPU0_SA_DQ<28>
J 0
(-6090 5285);
DISPLAY 0.659574 (-6090 5285);
PAINT MONO (-6090 5285);
DISPLAY INVISIBLE (-6090 5285);
FORCEPROP 1 LASTPIN (-6100 5275) BN 28
J 0
(-6112 5283);
DISPLAY 0.489362 (-6112 5283);
PAINT GREEN (-6112 5283);
FORCEPROP 2 LAST CDS_LIB mstr_standard
J 0
(-6050 5275);
DISPLAY 0.723404 (-6050 5275);
PAINT MONO (-6050 5275);
DISPLAY INVISIBLE (-6050 5275);
FORCEPROP 1 LAST BODY_TYPE PLUMBING
J 0
(-6050 5325);
DISPLAY 0.872340 (-6050 5325);
PAINT GREEN (-6050 5325);
DISPLAY INVISIBLE (-6050 5325);
FORCEPROP 1 LAST HDL_TAP TRUE
J 0
(-5725 5150);
DISPLAY 0.872340 (-5725 5150);
DISPLAY INVISIBLE (-5725 5150);
FORCEPROP 1 LAST PATH I447
J 0
(-6052 5275);
DISPLAY 0.872340 (-6052 5275);
PAINT GREEN (-6052 5275);
DISPLAY INVISIBLE (-6052 5275);
FORCEADD OFFPAGE..3
(-5500 5475);
FORCEPROP 2 LAST $XR0 10 
J 0
(-5286 5475);
DISPLAY 0.638298 (-5286 5475);
PAINT MONO (-5286 5475);
FORCEPROP 2 LAST CDS_LIB mstr_standard
J 0
(-5500 5475);
DISPLAY 0.723404 (-5500 5475);
PAINT MONO (-5500 5475);
DISPLAY INVISIBLE (-5500 5475);
FORCEPROP 1 LAST OFFPAGE TRUE
J 0
(-5175 5350);
DISPLAY 0.872340 (-5175 5350);
PAINT GREEN (-5175 5350);
DISPLAY INVISIBLE (-5175 5350);
FORCEPROP 1 LAST COMMENT_BODY TRUE
J 0
(-5550 5375);
DISPLAY 0.872340 (-5550 5375);
PAINT GREEN (-5550 5375);
DISPLAY INVISIBLE (-5550 5375);
FORCEPROP 2 LAST PATH I448
J 0
(-5275 5525);
DISPLAY 0.808511 (-5275 5525);
DISPLAY INVISIBLE (-5275 5525);
FORCEADD TAP..1
(-3600 3425);
FORCEPROP 3 LASTPIN (-3650 3425) SIG_NAME M_A_CPU0_SB_DQS_DP<0>
J 0
(-3640 3435);
DISPLAY 0.659574 (-3640 3435);
PAINT MONO (-3640 3435);
DISPLAY INVISIBLE (-3640 3435);
FORCEPROP 1 LASTPIN (-3650 3425) BN 0
J 0
(-3662 3433);
DISPLAY 0.489362 (-3662 3433);
PAINT GREEN (-3662 3433);
FORCEPROP 2 LAST CDS_LIB mstr_standard
J 0
(-3600 3425);
DISPLAY 0.723404 (-3600 3425);
PAINT MONO (-3600 3425);
DISPLAY INVISIBLE (-3600 3425);
FORCEPROP 1 LAST BODY_TYPE PLUMBING
J 0
(-3600 3475);
DISPLAY 0.872340 (-3600 3475);
PAINT GREEN (-3600 3475);
DISPLAY INVISIBLE (-3600 3475);
FORCEPROP 1 LAST HDL_TAP TRUE
J 0
(-3275 3300);
DISPLAY 0.872340 (-3275 3300);
DISPLAY INVISIBLE (-3275 3300);
FORCEPROP 1 LAST PATH I449
J 0
(-3602 3425);
DISPLAY 0.872340 (-3602 3425);
PAINT GREEN (-3602 3425);
DISPLAY INVISIBLE (-3602 3425);
FORCEADD TAP..1
(-3600 3525);
FORCEPROP 3 LASTPIN (-3650 3525) SIG_NAME M_A_CPU0_SB_DQS_DP<1>
J 0
(-3640 3535);
DISPLAY 0.659574 (-3640 3535);
PAINT MONO (-3640 3535);
DISPLAY INVISIBLE (-3640 3535);
FORCEPROP 1 LASTPIN (-3650 3525) BN 1
J 0
(-3662 3533);
DISPLAY 0.489362 (-3662 3533);
PAINT GREEN (-3662 3533);
FORCEPROP 2 LAST CDS_LIB mstr_standard
J 0
(-3600 3525);
DISPLAY 0.723404 (-3600 3525);
PAINT MONO (-3600 3525);
DISPLAY INVISIBLE (-3600 3525);
FORCEPROP 1 LAST BODY_TYPE PLUMBING
J 0
(-3600 3575);
DISPLAY 0.872340 (-3600 3575);
PAINT GREEN (-3600 3575);
DISPLAY INVISIBLE (-3600 3575);
FORCEPROP 1 LAST HDL_TAP TRUE
J 0
(-3275 3400);
DISPLAY 0.872340 (-3275 3400);
DISPLAY INVISIBLE (-3275 3400);
FORCEPROP 1 LAST PATH I450
J 0
(-3602 3525);
DISPLAY 0.872340 (-3602 3525);
PAINT GREEN (-3602 3525);
DISPLAY INVISIBLE (-3602 3525);
FORCEADD TAP..1
(-3400 3575);
FORCEPROP 3 LASTPIN (-3450 3575) SIG_NAME M_A_CPU0_SB_DQS_DN<2>
J 0
(-3440 3585);
DISPLAY 0.659574 (-3440 3585);
PAINT MONO (-3440 3585);
DISPLAY INVISIBLE (-3440 3585);
FORCEPROP 1 LASTPIN (-3450 3575) BN 2
J 0
(-3462 3583);
DISPLAY 0.489362 (-3462 3583);
PAINT GREEN (-3462 3583);
FORCEPROP 2 LAST CDS_LIB mstr_standard
J 0
(-3400 3575);
DISPLAY 0.723404 (-3400 3575);
PAINT MONO (-3400 3575);
DISPLAY INVISIBLE (-3400 3575);
FORCEPROP 1 LAST BODY_TYPE PLUMBING
J 0
(-3400 3625);
DISPLAY 0.872340 (-3400 3625);
PAINT GREEN (-3400 3625);
DISPLAY INVISIBLE (-3400 3625);
FORCEPROP 1 LAST HDL_TAP TRUE
J 0
(-3075 3450);
DISPLAY 0.872340 (-3075 3450);
DISPLAY INVISIBLE (-3075 3450);
FORCEPROP 1 LAST PATH I451
J 0
(-3402 3575);
DISPLAY 0.872340 (-3402 3575);
PAINT GREEN (-3402 3575);
DISPLAY INVISIBLE (-3402 3575);
FORCEADD TAP..1
(-3400 3475);
FORCEPROP 3 LASTPIN (-3450 3475) SIG_NAME M_A_CPU0_SB_DQS_DN<1>
J 0
(-3440 3485);
DISPLAY 0.659574 (-3440 3485);
PAINT MONO (-3440 3485);
DISPLAY INVISIBLE (-3440 3485);
FORCEPROP 1 LASTPIN (-3450 3475) BN 1
J 0
(-3462 3483);
DISPLAY 0.489362 (-3462 3483);
PAINT GREEN (-3462 3483);
FORCEPROP 2 LAST CDS_LIB mstr_standard
J 0
(-3400 3475);
DISPLAY 0.723404 (-3400 3475);
PAINT MONO (-3400 3475);
DISPLAY INVISIBLE (-3400 3475);
FORCEPROP 1 LAST BODY_TYPE PLUMBING
J 0
(-3400 3525);
DISPLAY 0.872340 (-3400 3525);
PAINT GREEN (-3400 3525);
DISPLAY INVISIBLE (-3400 3525);
FORCEPROP 1 LAST HDL_TAP TRUE
J 0
(-3075 3350);
DISPLAY 0.872340 (-3075 3350);
DISPLAY INVISIBLE (-3075 3350);
FORCEPROP 1 LAST PATH I452
J 0
(-3402 3475);
DISPLAY 0.872340 (-3402 3475);
PAINT GREEN (-3402 3475);
DISPLAY INVISIBLE (-3402 3475);
FORCEADD TAP..1
(-3400 3375);
FORCEPROP 3 LASTPIN (-3450 3375) SIG_NAME M_A_CPU0_SB_DQS_DN<0>
J 0
(-3440 3385);
DISPLAY 0.659574 (-3440 3385);
PAINT MONO (-3440 3385);
DISPLAY INVISIBLE (-3440 3385);
FORCEPROP 1 LASTPIN (-3450 3375) BN 0
J 0
(-3462 3383);
DISPLAY 0.489362 (-3462 3383);
PAINT GREEN (-3462 3383);
FORCEPROP 2 LAST CDS_LIB mstr_standard
J 0
(-3400 3375);
DISPLAY 0.723404 (-3400 3375);
PAINT MONO (-3400 3375);
DISPLAY INVISIBLE (-3400 3375);
FORCEPROP 1 LAST BODY_TYPE PLUMBING
J 0
(-3400 3425);
DISPLAY 0.872340 (-3400 3425);
PAINT GREEN (-3400 3425);
DISPLAY INVISIBLE (-3400 3425);
FORCEPROP 1 LAST HDL_TAP TRUE
J 0
(-3075 3250);
DISPLAY 0.872340 (-3075 3250);
DISPLAY INVISIBLE (-3075 3250);
FORCEPROP 1 LAST PATH I453
J 0
(-3402 3375);
DISPLAY 0.872340 (-3402 3375);
PAINT GREEN (-3402 3375);
DISPLAY INVISIBLE (-3402 3375);
FORCEADD TAP..1
(-3600 3625);
FORCEPROP 3 LASTPIN (-3650 3625) SIG_NAME M_A_CPU0_SB_DQS_DP<2>
J 0
(-3640 3635);
DISPLAY 0.659574 (-3640 3635);
PAINT MONO (-3640 3635);
DISPLAY INVISIBLE (-3640 3635);
FORCEPROP 1 LASTPIN (-3650 3625) BN 2
J 0
(-3662 3633);
DISPLAY 0.489362 (-3662 3633);
PAINT GREEN (-3662 3633);
FORCEPROP 2 LAST CDS_LIB mstr_standard
J 0
(-3600 3625);
DISPLAY 0.723404 (-3600 3625);
PAINT MONO (-3600 3625);
DISPLAY INVISIBLE (-3600 3625);
FORCEPROP 1 LAST BODY_TYPE PLUMBING
J 0
(-3600 3675);
DISPLAY 0.872340 (-3600 3675);
PAINT GREEN (-3600 3675);
DISPLAY INVISIBLE (-3600 3675);
FORCEPROP 1 LAST HDL_TAP TRUE
J 0
(-3275 3500);
DISPLAY 0.872340 (-3275 3500);
DISPLAY INVISIBLE (-3275 3500);
FORCEPROP 1 LAST PATH I454
J 0
(-3602 3625);
DISPLAY 0.872340 (-3602 3625);
PAINT GREEN (-3602 3625);
DISPLAY INVISIBLE (-3602 3625);
FORCEADD TAP..1
(-3600 3725);
FORCEPROP 3 LASTPIN (-3650 3725) SIG_NAME M_A_CPU0_SB_DQS_DP<3>
J 0
(-3640 3735);
DISPLAY 0.659574 (-3640 3735);
PAINT MONO (-3640 3735);
DISPLAY INVISIBLE (-3640 3735);
FORCEPROP 1 LASTPIN (-3650 3725) BN 3
J 0
(-3662 3733);
DISPLAY 0.489362 (-3662 3733);
PAINT GREEN (-3662 3733);
FORCEPROP 2 LAST CDS_LIB mstr_standard
J 0
(-3600 3725);
DISPLAY 0.723404 (-3600 3725);
PAINT MONO (-3600 3725);
DISPLAY INVISIBLE (-3600 3725);
FORCEPROP 1 LAST BODY_TYPE PLUMBING
J 0
(-3600 3775);
DISPLAY 0.872340 (-3600 3775);
PAINT GREEN (-3600 3775);
DISPLAY INVISIBLE (-3600 3775);
FORCEPROP 1 LAST HDL_TAP TRUE
J 0
(-3275 3600);
DISPLAY 0.872340 (-3275 3600);
DISPLAY INVISIBLE (-3275 3600);
FORCEPROP 1 LAST PATH I455
J 0
(-3602 3725);
DISPLAY 0.872340 (-3602 3725);
PAINT GREEN (-3602 3725);
DISPLAY INVISIBLE (-3602 3725);
FORCEADD TAP..1
(-3600 3825);
FORCEPROP 3 LASTPIN (-3650 3825) SIG_NAME M_A_CPU0_SB_DQS_DP<4>
J 0
(-3640 3835);
DISPLAY 0.659574 (-3640 3835);
PAINT MONO (-3640 3835);
DISPLAY INVISIBLE (-3640 3835);
FORCEPROP 1 LASTPIN (-3650 3825) BN 4
J 0
(-3662 3833);
DISPLAY 0.489362 (-3662 3833);
PAINT GREEN (-3662 3833);
FORCEPROP 2 LAST CDS_LIB mstr_standard
J 0
(-3600 3825);
DISPLAY 0.723404 (-3600 3825);
PAINT MONO (-3600 3825);
DISPLAY INVISIBLE (-3600 3825);
FORCEPROP 1 LAST BODY_TYPE PLUMBING
J 0
(-3600 3875);
DISPLAY 0.872340 (-3600 3875);
PAINT GREEN (-3600 3875);
DISPLAY INVISIBLE (-3600 3875);
FORCEPROP 1 LAST HDL_TAP TRUE
J 0
(-3275 3700);
DISPLAY 0.872340 (-3275 3700);
DISPLAY INVISIBLE (-3275 3700);
FORCEPROP 1 LAST PATH I456
J 0
(-3602 3825);
DISPLAY 0.872340 (-3602 3825);
PAINT GREEN (-3602 3825);
DISPLAY INVISIBLE (-3602 3825);
FORCEADD TAP..1
(-3400 3675);
FORCEPROP 3 LASTPIN (-3450 3675) SIG_NAME M_A_CPU0_SB_DQS_DN<3>
J 0
(-3440 3685);
DISPLAY 0.659574 (-3440 3685);
PAINT MONO (-3440 3685);
DISPLAY INVISIBLE (-3440 3685);
FORCEPROP 1 LASTPIN (-3450 3675) BN 3
J 0
(-3462 3683);
DISPLAY 0.489362 (-3462 3683);
PAINT GREEN (-3462 3683);
FORCEPROP 2 LAST CDS_LIB mstr_standard
J 0
(-3400 3675);
DISPLAY 0.723404 (-3400 3675);
PAINT MONO (-3400 3675);
DISPLAY INVISIBLE (-3400 3675);
FORCEPROP 1 LAST BODY_TYPE PLUMBING
J 0
(-3400 3725);
DISPLAY 0.872340 (-3400 3725);
PAINT GREEN (-3400 3725);
DISPLAY INVISIBLE (-3400 3725);
FORCEPROP 1 LAST HDL_TAP TRUE
J 0
(-3075 3550);
DISPLAY 0.872340 (-3075 3550);
DISPLAY INVISIBLE (-3075 3550);
FORCEPROP 1 LAST PATH I457
J 0
(-3402 3675);
DISPLAY 0.872340 (-3402 3675);
PAINT GREEN (-3402 3675);
DISPLAY INVISIBLE (-3402 3675);
FORCEADD TAP..1
(-3400 3775);
FORCEPROP 3 LASTPIN (-3450 3775) SIG_NAME M_A_CPU0_SB_DQS_DN<4>
J 0
(-3440 3785);
DISPLAY 0.659574 (-3440 3785);
PAINT MONO (-3440 3785);
DISPLAY INVISIBLE (-3440 3785);
FORCEPROP 1 LASTPIN (-3450 3775) BN 4
J 0
(-3462 3783);
DISPLAY 0.489362 (-3462 3783);
PAINT GREEN (-3462 3783);
FORCEPROP 2 LAST CDS_LIB mstr_standard
J 0
(-3400 3775);
DISPLAY 0.723404 (-3400 3775);
PAINT MONO (-3400 3775);
DISPLAY INVISIBLE (-3400 3775);
FORCEPROP 1 LAST BODY_TYPE PLUMBING
J 0
(-3400 3825);
DISPLAY 0.872340 (-3400 3825);
PAINT GREEN (-3400 3825);
DISPLAY INVISIBLE (-3400 3825);
FORCEPROP 1 LAST HDL_TAP TRUE
J 0
(-3075 3650);
DISPLAY 0.872340 (-3075 3650);
DISPLAY INVISIBLE (-3075 3650);
FORCEPROP 1 LAST PATH I458
J 0
(-3402 3775);
DISPLAY 0.872340 (-3402 3775);
PAINT GREEN (-3402 3775);
DISPLAY INVISIBLE (-3402 3775);
FORCEADD TAP..1
(-3600 3925);
FORCEPROP 3 LASTPIN (-3650 3925) SIG_NAME M_A_CPU0_SB_DQS_DP<5>
J 0
(-3640 3935);
DISPLAY 0.659574 (-3640 3935);
PAINT MONO (-3640 3935);
DISPLAY INVISIBLE (-3640 3935);
FORCEPROP 1 LASTPIN (-3650 3925) BN 5
J 0
(-3662 3933);
DISPLAY 0.489362 (-3662 3933);
PAINT GREEN (-3662 3933);
FORCEPROP 2 LAST CDS_LIB mstr_standard
J 0
(-3600 3925);
DISPLAY 0.723404 (-3600 3925);
PAINT MONO (-3600 3925);
DISPLAY INVISIBLE (-3600 3925);
FORCEPROP 1 LAST BODY_TYPE PLUMBING
J 0
(-3600 3975);
DISPLAY 0.872340 (-3600 3975);
PAINT GREEN (-3600 3975);
DISPLAY INVISIBLE (-3600 3975);
FORCEPROP 1 LAST HDL_TAP TRUE
J 0
(-3275 3800);
DISPLAY 0.872340 (-3275 3800);
DISPLAY INVISIBLE (-3275 3800);
FORCEPROP 1 LAST PATH I459
J 0
(-3602 3925);
DISPLAY 0.872340 (-3602 3925);
PAINT GREEN (-3602 3925);
DISPLAY INVISIBLE (-3602 3925);
FORCEADD TAP..1
(-3600 4025);
FORCEPROP 3 LASTPIN (-3650 4025) SIG_NAME M_A_CPU0_SB_DQS_DP<6>
J 0
(-3640 4035);
DISPLAY 0.659574 (-3640 4035);
PAINT MONO (-3640 4035);
DISPLAY INVISIBLE (-3640 4035);
FORCEPROP 1 LASTPIN (-3650 4025) BN 6
J 0
(-3662 4033);
DISPLAY 0.489362 (-3662 4033);
PAINT GREEN (-3662 4033);
FORCEPROP 2 LAST CDS_LIB mstr_standard
J 0
(-3600 4025);
DISPLAY 0.723404 (-3600 4025);
PAINT MONO (-3600 4025);
DISPLAY INVISIBLE (-3600 4025);
FORCEPROP 1 LAST BODY_TYPE PLUMBING
J 0
(-3600 4075);
DISPLAY 0.872340 (-3600 4075);
PAINT GREEN (-3600 4075);
DISPLAY INVISIBLE (-3600 4075);
FORCEPROP 1 LAST HDL_TAP TRUE
J 0
(-3275 3900);
DISPLAY 0.872340 (-3275 3900);
DISPLAY INVISIBLE (-3275 3900);
FORCEPROP 1 LAST PATH I460
J 0
(-3602 4025);
DISPLAY 0.872340 (-3602 4025);
PAINT GREEN (-3602 4025);
DISPLAY INVISIBLE (-3602 4025);
FORCEADD TAP..1
(-3400 4075);
FORCEPROP 3 LASTPIN (-3450 4075) SIG_NAME M_A_CPU0_SB_DQS_DN<7>
J 0
(-3440 4085);
DISPLAY 0.659574 (-3440 4085);
PAINT MONO (-3440 4085);
DISPLAY INVISIBLE (-3440 4085);
FORCEPROP 1 LASTPIN (-3450 4075) BN 7
J 0
(-3462 4083);
DISPLAY 0.489362 (-3462 4083);
PAINT GREEN (-3462 4083);
FORCEPROP 2 LAST CDS_LIB mstr_standard
J 0
(-3400 4075);
DISPLAY 0.723404 (-3400 4075);
PAINT MONO (-3400 4075);
DISPLAY INVISIBLE (-3400 4075);
FORCEPROP 1 LAST BODY_TYPE PLUMBING
J 0
(-3400 4125);
DISPLAY 0.872340 (-3400 4125);
PAINT GREEN (-3400 4125);
DISPLAY INVISIBLE (-3400 4125);
FORCEPROP 1 LAST HDL_TAP TRUE
J 0
(-3075 3950);
DISPLAY 0.872340 (-3075 3950);
DISPLAY INVISIBLE (-3075 3950);
FORCEPROP 1 LAST PATH I461
J 0
(-3402 4075);
DISPLAY 0.872340 (-3402 4075);
PAINT GREEN (-3402 4075);
DISPLAY INVISIBLE (-3402 4075);
FORCEADD TAP..1
(-3400 3975);
FORCEPROP 3 LASTPIN (-3450 3975) SIG_NAME M_A_CPU0_SB_DQS_DN<6>
J 0
(-3440 3985);
DISPLAY 0.659574 (-3440 3985);
PAINT MONO (-3440 3985);
DISPLAY INVISIBLE (-3440 3985);
FORCEPROP 1 LASTPIN (-3450 3975) BN 6
J 0
(-3462 3983);
DISPLAY 0.489362 (-3462 3983);
PAINT GREEN (-3462 3983);
FORCEPROP 2 LAST CDS_LIB mstr_standard
J 0
(-3400 3975);
DISPLAY 0.723404 (-3400 3975);
PAINT MONO (-3400 3975);
DISPLAY INVISIBLE (-3400 3975);
FORCEPROP 1 LAST BODY_TYPE PLUMBING
J 0
(-3400 4025);
DISPLAY 0.872340 (-3400 4025);
PAINT GREEN (-3400 4025);
DISPLAY INVISIBLE (-3400 4025);
FORCEPROP 1 LAST HDL_TAP TRUE
J 0
(-3075 3850);
DISPLAY 0.872340 (-3075 3850);
DISPLAY INVISIBLE (-3075 3850);
FORCEPROP 1 LAST PATH I462
J 0
(-3402 3975);
DISPLAY 0.872340 (-3402 3975);
PAINT GREEN (-3402 3975);
DISPLAY INVISIBLE (-3402 3975);
FORCEADD TAP..1
(-3400 3875);
FORCEPROP 3 LASTPIN (-3450 3875) SIG_NAME M_A_CPU0_SB_DQS_DN<5>
J 0
(-3440 3885);
DISPLAY 0.659574 (-3440 3885);
PAINT MONO (-3440 3885);
DISPLAY INVISIBLE (-3440 3885);
FORCEPROP 1 LASTPIN (-3450 3875) BN 5
J 0
(-3462 3883);
DISPLAY 0.489362 (-3462 3883);
PAINT GREEN (-3462 3883);
FORCEPROP 2 LAST CDS_LIB mstr_standard
J 0
(-3400 3875);
DISPLAY 0.723404 (-3400 3875);
PAINT MONO (-3400 3875);
DISPLAY INVISIBLE (-3400 3875);
FORCEPROP 1 LAST BODY_TYPE PLUMBING
J 0
(-3400 3925);
DISPLAY 0.872340 (-3400 3925);
PAINT GREEN (-3400 3925);
DISPLAY INVISIBLE (-3400 3925);
FORCEPROP 1 LAST HDL_TAP TRUE
J 0
(-3075 3750);
DISPLAY 0.872340 (-3075 3750);
DISPLAY INVISIBLE (-3075 3750);
FORCEPROP 1 LAST PATH I463
J 0
(-3402 3875);
DISPLAY 0.872340 (-3402 3875);
PAINT GREEN (-3402 3875);
DISPLAY INVISIBLE (-3402 3875);
FORCEADD TAP..1
(-3600 4125);
FORCEPROP 3 LASTPIN (-3650 4125) SIG_NAME M_A_CPU0_SB_DQS_DP<7>
J 0
(-3640 4135);
DISPLAY 0.659574 (-3640 4135);
PAINT MONO (-3640 4135);
DISPLAY INVISIBLE (-3640 4135);
FORCEPROP 1 LASTPIN (-3650 4125) BN 7
J 0
(-3662 4133);
DISPLAY 0.489362 (-3662 4133);
PAINT GREEN (-3662 4133);
FORCEPROP 2 LAST CDS_LIB mstr_standard
J 0
(-3600 4125);
DISPLAY 0.723404 (-3600 4125);
PAINT MONO (-3600 4125);
DISPLAY INVISIBLE (-3600 4125);
FORCEPROP 1 LAST BODY_TYPE PLUMBING
J 0
(-3600 4175);
DISPLAY 0.872340 (-3600 4175);
PAINT GREEN (-3600 4175);
DISPLAY INVISIBLE (-3600 4175);
FORCEPROP 1 LAST HDL_TAP TRUE
J 0
(-3275 4000);
DISPLAY 0.872340 (-3275 4000);
DISPLAY INVISIBLE (-3275 4000);
FORCEPROP 1 LAST PATH I464
J 0
(-3602 4125);
DISPLAY 0.872340 (-3602 4125);
PAINT GREEN (-3602 4125);
DISPLAY INVISIBLE (-3602 4125);
FORCEADD TAP..1
(-3600 4225);
FORCEPROP 3 LASTPIN (-3650 4225) SIG_NAME M_A_CPU0_SB_DQS_DP<8>
J 0
(-3640 4235);
DISPLAY 0.659574 (-3640 4235);
PAINT MONO (-3640 4235);
DISPLAY INVISIBLE (-3640 4235);
FORCEPROP 1 LASTPIN (-3650 4225) BN 8
J 0
(-3662 4233);
DISPLAY 0.489362 (-3662 4233);
PAINT GREEN (-3662 4233);
FORCEPROP 2 LAST CDS_LIB mstr_standard
J 0
(-3600 4225);
DISPLAY 0.723404 (-3600 4225);
PAINT MONO (-3600 4225);
DISPLAY INVISIBLE (-3600 4225);
FORCEPROP 1 LAST BODY_TYPE PLUMBING
J 0
(-3600 4275);
DISPLAY 0.872340 (-3600 4275);
PAINT GREEN (-3600 4275);
DISPLAY INVISIBLE (-3600 4275);
FORCEPROP 1 LAST HDL_TAP TRUE
J 0
(-3275 4100);
DISPLAY 0.872340 (-3275 4100);
DISPLAY INVISIBLE (-3275 4100);
FORCEPROP 1 LAST PATH I465
J 0
(-3602 4225);
DISPLAY 0.872340 (-3602 4225);
PAINT GREEN (-3602 4225);
DISPLAY INVISIBLE (-3602 4225);
FORCEADD TAP..1
(-3600 4325);
FORCEPROP 3 LASTPIN (-3650 4325) SIG_NAME M_A_CPU0_SB_DQS_DP<9>
J 0
(-3640 4335);
DISPLAY 0.659574 (-3640 4335);
PAINT MONO (-3640 4335);
DISPLAY INVISIBLE (-3640 4335);
FORCEPROP 1 LASTPIN (-3650 4325) BN 9
J 0
(-3662 4333);
DISPLAY 0.489362 (-3662 4333);
PAINT GREEN (-3662 4333);
FORCEPROP 2 LAST CDS_LIB mstr_standard
J 0
(-3600 4325);
DISPLAY 0.723404 (-3600 4325);
PAINT MONO (-3600 4325);
DISPLAY INVISIBLE (-3600 4325);
FORCEPROP 1 LAST BODY_TYPE PLUMBING
J 0
(-3600 4375);
DISPLAY 0.872340 (-3600 4375);
PAINT GREEN (-3600 4375);
DISPLAY INVISIBLE (-3600 4375);
FORCEPROP 1 LAST HDL_TAP TRUE
J 0
(-3275 4200);
DISPLAY 0.872340 (-3275 4200);
DISPLAY INVISIBLE (-3275 4200);
FORCEPROP 1 LAST PATH I466
J 0
(-3602 4325);
DISPLAY 0.872340 (-3602 4325);
PAINT GREEN (-3602 4325);
DISPLAY INVISIBLE (-3602 4325);
FORCEADD TAP..1
(-3400 4175);
FORCEPROP 3 LASTPIN (-3450 4175) SIG_NAME M_A_CPU0_SB_DQS_DN<8>
J 0
(-3440 4185);
DISPLAY 0.659574 (-3440 4185);
PAINT MONO (-3440 4185);
DISPLAY INVISIBLE (-3440 4185);
FORCEPROP 1 LASTPIN (-3450 4175) BN 8
J 0
(-3462 4183);
DISPLAY 0.489362 (-3462 4183);
PAINT GREEN (-3462 4183);
FORCEPROP 2 LAST CDS_LIB mstr_standard
J 0
(-3400 4175);
DISPLAY 0.723404 (-3400 4175);
PAINT MONO (-3400 4175);
DISPLAY INVISIBLE (-3400 4175);
FORCEPROP 1 LAST BODY_TYPE PLUMBING
J 0
(-3400 4225);
DISPLAY 0.872340 (-3400 4225);
PAINT GREEN (-3400 4225);
DISPLAY INVISIBLE (-3400 4225);
FORCEPROP 1 LAST HDL_TAP TRUE
J 0
(-3075 4050);
DISPLAY 0.872340 (-3075 4050);
DISPLAY INVISIBLE (-3075 4050);
FORCEPROP 1 LAST PATH I467
J 0
(-3402 4175);
DISPLAY 0.872340 (-3402 4175);
PAINT GREEN (-3402 4175);
DISPLAY INVISIBLE (-3402 4175);
FORCEADD TAP..1
(-3400 4275);
FORCEPROP 3 LASTPIN (-3450 4275) SIG_NAME M_A_CPU0_SB_DQS_DN<9>
J 0
(-3440 4285);
DISPLAY 0.659574 (-3440 4285);
PAINT MONO (-3440 4285);
DISPLAY INVISIBLE (-3440 4285);
FORCEPROP 1 LASTPIN (-3450 4275) BN 9
J 0
(-3462 4283);
DISPLAY 0.489362 (-3462 4283);
PAINT GREEN (-3462 4283);
FORCEPROP 2 LAST CDS_LIB mstr_standard
J 0
(-3400 4275);
DISPLAY 0.723404 (-3400 4275);
PAINT MONO (-3400 4275);
DISPLAY INVISIBLE (-3400 4275);
FORCEPROP 1 LAST BODY_TYPE PLUMBING
J 0
(-3400 4325);
DISPLAY 0.872340 (-3400 4325);
PAINT GREEN (-3400 4325);
DISPLAY INVISIBLE (-3400 4325);
FORCEPROP 1 LAST HDL_TAP TRUE
J 0
(-3075 4150);
DISPLAY 0.872340 (-3075 4150);
DISPLAY INVISIBLE (-3075 4150);
FORCEPROP 1 LAST PATH I468
J 0
(-3402 4275);
DISPLAY 0.872340 (-3402 4275);
PAINT GREEN (-3402 4275);
DISPLAY INVISIBLE (-3402 4275);
FORCEADD TAP..1
(-3600 4475);
FORCEPROP 3 LASTPIN (-3650 4475) SIG_NAME M_A_CPU0_SA_DQS_DP<0>
J 0
(-3640 4485);
DISPLAY 0.659574 (-3640 4485);
PAINT MONO (-3640 4485);
DISPLAY INVISIBLE (-3640 4485);
FORCEPROP 1 LASTPIN (-3650 4475) BN 0
J 0
(-3662 4483);
DISPLAY 0.489362 (-3662 4483);
PAINT GREEN (-3662 4483);
FORCEPROP 2 LAST CDS_LIB mstr_standard
J 0
(-3600 4475);
DISPLAY 0.723404 (-3600 4475);
PAINT MONO (-3600 4475);
DISPLAY INVISIBLE (-3600 4475);
FORCEPROP 1 LAST BODY_TYPE PLUMBING
J 0
(-3600 4525);
DISPLAY 0.872340 (-3600 4525);
PAINT GREEN (-3600 4525);
DISPLAY INVISIBLE (-3600 4525);
FORCEPROP 1 LAST HDL_TAP TRUE
J 0
(-3275 4350);
DISPLAY 0.872340 (-3275 4350);
DISPLAY INVISIBLE (-3275 4350);
FORCEPROP 1 LAST PATH I469
J 0
(-3602 4475);
DISPLAY 0.872340 (-3602 4475);
PAINT GREEN (-3602 4475);
DISPLAY INVISIBLE (-3602 4475);
FORCEADD TAP..1
(-3600 4575);
FORCEPROP 3 LASTPIN (-3650 4575) SIG_NAME M_A_CPU0_SA_DQS_DP<1>
J 0
(-3640 4585);
DISPLAY 0.659574 (-3640 4585);
PAINT MONO (-3640 4585);
DISPLAY INVISIBLE (-3640 4585);
FORCEPROP 1 LASTPIN (-3650 4575) BN 1
J 0
(-3662 4583);
DISPLAY 0.489362 (-3662 4583);
PAINT GREEN (-3662 4583);
FORCEPROP 2 LAST CDS_LIB mstr_standard
J 0
(-3600 4575);
DISPLAY 0.723404 (-3600 4575);
PAINT MONO (-3600 4575);
DISPLAY INVISIBLE (-3600 4575);
FORCEPROP 1 LAST BODY_TYPE PLUMBING
J 0
(-3600 4625);
DISPLAY 0.872340 (-3600 4625);
PAINT GREEN (-3600 4625);
DISPLAY INVISIBLE (-3600 4625);
FORCEPROP 1 LAST HDL_TAP TRUE
J 0
(-3275 4450);
DISPLAY 0.872340 (-3275 4450);
DISPLAY INVISIBLE (-3275 4450);
FORCEPROP 1 LAST PATH I470
J 0
(-3602 4575);
DISPLAY 0.872340 (-3602 4575);
PAINT GREEN (-3602 4575);
DISPLAY INVISIBLE (-3602 4575);
FORCEADD TAP..1
(-3400 4425);
FORCEPROP 3 LASTPIN (-3450 4425) SIG_NAME M_A_CPU0_SA_DQS_DN<0>
J 0
(-3440 4435);
DISPLAY 0.659574 (-3440 4435);
PAINT MONO (-3440 4435);
DISPLAY INVISIBLE (-3440 4435);
FORCEPROP 1 LASTPIN (-3450 4425) BN 0
J 0
(-3462 4433);
DISPLAY 0.489362 (-3462 4433);
PAINT GREEN (-3462 4433);
FORCEPROP 2 LAST CDS_LIB mstr_standard
J 0
(-3400 4425);
DISPLAY 0.723404 (-3400 4425);
PAINT MONO (-3400 4425);
DISPLAY INVISIBLE (-3400 4425);
FORCEPROP 1 LAST BODY_TYPE PLUMBING
J 0
(-3400 4475);
DISPLAY 0.872340 (-3400 4475);
PAINT GREEN (-3400 4475);
DISPLAY INVISIBLE (-3400 4475);
FORCEPROP 1 LAST HDL_TAP TRUE
J 0
(-3075 4300);
DISPLAY 0.872340 (-3075 4300);
DISPLAY INVISIBLE (-3075 4300);
FORCEPROP 1 LAST PATH I471
J 0
(-3402 4425);
DISPLAY 0.872340 (-3402 4425);
PAINT GREEN (-3402 4425);
DISPLAY INVISIBLE (-3402 4425);
FORCEADD TAP..1
(-3400 4525);
FORCEPROP 3 LASTPIN (-3450 4525) SIG_NAME M_A_CPU0_SA_DQS_DN<1>
J 0
(-3440 4535);
DISPLAY 0.659574 (-3440 4535);
PAINT MONO (-3440 4535);
DISPLAY INVISIBLE (-3440 4535);
FORCEPROP 1 LASTPIN (-3450 4525) BN 1
J 0
(-3462 4533);
DISPLAY 0.489362 (-3462 4533);
PAINT GREEN (-3462 4533);
FORCEPROP 2 LAST CDS_LIB mstr_standard
J 0
(-3400 4525);
DISPLAY 0.723404 (-3400 4525);
PAINT MONO (-3400 4525);
DISPLAY INVISIBLE (-3400 4525);
FORCEPROP 1 LAST BODY_TYPE PLUMBING
J 0
(-3400 4575);
DISPLAY 0.872340 (-3400 4575);
PAINT GREEN (-3400 4575);
DISPLAY INVISIBLE (-3400 4575);
FORCEPROP 1 LAST HDL_TAP TRUE
J 0
(-3075 4400);
DISPLAY 0.872340 (-3075 4400);
DISPLAY INVISIBLE (-3075 4400);
FORCEPROP 1 LAST PATH I472
J 0
(-3402 4525);
DISPLAY 0.872340 (-3402 4525);
PAINT GREEN (-3402 4525);
DISPLAY INVISIBLE (-3402 4525);
FORCEADD TAP..1
(-3600 4675);
FORCEPROP 3 LASTPIN (-3650 4675) SIG_NAME M_A_CPU0_SA_DQS_DP<2>
J 0
(-3640 4685);
DISPLAY 0.659574 (-3640 4685);
PAINT MONO (-3640 4685);
DISPLAY INVISIBLE (-3640 4685);
FORCEPROP 1 LASTPIN (-3650 4675) BN 2
J 0
(-3662 4683);
DISPLAY 0.489362 (-3662 4683);
PAINT GREEN (-3662 4683);
FORCEPROP 2 LAST CDS_LIB mstr_standard
J 0
(-3600 4675);
DISPLAY 0.723404 (-3600 4675);
PAINT MONO (-3600 4675);
DISPLAY INVISIBLE (-3600 4675);
FORCEPROP 1 LAST BODY_TYPE PLUMBING
J 0
(-3600 4725);
DISPLAY 0.872340 (-3600 4725);
PAINT GREEN (-3600 4725);
DISPLAY INVISIBLE (-3600 4725);
FORCEPROP 1 LAST HDL_TAP TRUE
J 0
(-3275 4550);
DISPLAY 0.872340 (-3275 4550);
DISPLAY INVISIBLE (-3275 4550);
FORCEPROP 1 LAST PATH I473
J 0
(-3602 4675);
DISPLAY 0.872340 (-3602 4675);
PAINT GREEN (-3602 4675);
DISPLAY INVISIBLE (-3602 4675);
FORCEADD TAP..1
(-3600 4775);
FORCEPROP 3 LASTPIN (-3650 4775) SIG_NAME M_A_CPU0_SA_DQS_DP<3>
J 0
(-3640 4785);
DISPLAY 0.659574 (-3640 4785);
PAINT MONO (-3640 4785);
DISPLAY INVISIBLE (-3640 4785);
FORCEPROP 1 LASTPIN (-3650 4775) BN 3
J 0
(-3662 4783);
DISPLAY 0.489362 (-3662 4783);
PAINT GREEN (-3662 4783);
FORCEPROP 2 LAST CDS_LIB mstr_standard
J 0
(-3600 4775);
DISPLAY 0.723404 (-3600 4775);
PAINT MONO (-3600 4775);
DISPLAY INVISIBLE (-3600 4775);
FORCEPROP 1 LAST BODY_TYPE PLUMBING
J 0
(-3600 4825);
DISPLAY 0.872340 (-3600 4825);
PAINT GREEN (-3600 4825);
DISPLAY INVISIBLE (-3600 4825);
FORCEPROP 1 LAST HDL_TAP TRUE
J 0
(-3275 4650);
DISPLAY 0.872340 (-3275 4650);
DISPLAY INVISIBLE (-3275 4650);
FORCEPROP 1 LAST PATH I474
J 0
(-3602 4775);
DISPLAY 0.872340 (-3602 4775);
PAINT GREEN (-3602 4775);
DISPLAY INVISIBLE (-3602 4775);
FORCEADD TAP..1
(-3400 4625);
FORCEPROP 3 LASTPIN (-3450 4625) SIG_NAME M_A_CPU0_SA_DQS_DN<2>
J 0
(-3440 4635);
DISPLAY 0.659574 (-3440 4635);
PAINT MONO (-3440 4635);
DISPLAY INVISIBLE (-3440 4635);
FORCEPROP 1 LASTPIN (-3450 4625) BN 2
J 0
(-3462 4633);
DISPLAY 0.489362 (-3462 4633);
PAINT GREEN (-3462 4633);
FORCEPROP 2 LAST CDS_LIB mstr_standard
J 0
(-3400 4625);
DISPLAY 0.723404 (-3400 4625);
PAINT MONO (-3400 4625);
DISPLAY INVISIBLE (-3400 4625);
FORCEPROP 1 LAST BODY_TYPE PLUMBING
J 0
(-3400 4675);
DISPLAY 0.872340 (-3400 4675);
PAINT GREEN (-3400 4675);
DISPLAY INVISIBLE (-3400 4675);
FORCEPROP 1 LAST HDL_TAP TRUE
J 0
(-3075 4500);
DISPLAY 0.872340 (-3075 4500);
DISPLAY INVISIBLE (-3075 4500);
FORCEPROP 1 LAST PATH I475
J 0
(-3402 4625);
DISPLAY 0.872340 (-3402 4625);
PAINT GREEN (-3402 4625);
DISPLAY INVISIBLE (-3402 4625);
FORCEADD TAP..1
(-3400 4725);
FORCEPROP 3 LASTPIN (-3450 4725) SIG_NAME M_A_CPU0_SA_DQS_DN<3>
J 0
(-3440 4735);
DISPLAY 0.659574 (-3440 4735);
PAINT MONO (-3440 4735);
DISPLAY INVISIBLE (-3440 4735);
FORCEPROP 1 LASTPIN (-3450 4725) BN 3
J 0
(-3462 4733);
DISPLAY 0.489362 (-3462 4733);
PAINT GREEN (-3462 4733);
FORCEPROP 2 LAST CDS_LIB mstr_standard
J 0
(-3400 4725);
DISPLAY 0.723404 (-3400 4725);
PAINT MONO (-3400 4725);
DISPLAY INVISIBLE (-3400 4725);
FORCEPROP 1 LAST BODY_TYPE PLUMBING
J 0
(-3400 4775);
DISPLAY 0.872340 (-3400 4775);
PAINT GREEN (-3400 4775);
DISPLAY INVISIBLE (-3400 4775);
FORCEPROP 1 LAST HDL_TAP TRUE
J 0
(-3075 4600);
DISPLAY 0.872340 (-3075 4600);
DISPLAY INVISIBLE (-3075 4600);
FORCEPROP 1 LAST PATH I476
J 0
(-3402 4725);
DISPLAY 0.872340 (-3402 4725);
PAINT GREEN (-3402 4725);
DISPLAY INVISIBLE (-3402 4725);
FORCEADD TAP..1
(-3400 4825);
FORCEPROP 3 LASTPIN (-3450 4825) SIG_NAME M_A_CPU0_SA_DQS_DN<4>
J 0
(-3440 4835);
DISPLAY 0.659574 (-3440 4835);
PAINT MONO (-3440 4835);
DISPLAY INVISIBLE (-3440 4835);
FORCEPROP 1 LASTPIN (-3450 4825) BN 4
J 0
(-3462 4833);
DISPLAY 0.489362 (-3462 4833);
PAINT GREEN (-3462 4833);
FORCEPROP 2 LAST CDS_LIB mstr_standard
J 0
(-3400 4825);
DISPLAY 0.723404 (-3400 4825);
PAINT MONO (-3400 4825);
DISPLAY INVISIBLE (-3400 4825);
FORCEPROP 1 LAST BODY_TYPE PLUMBING
J 0
(-3400 4875);
DISPLAY 0.872340 (-3400 4875);
PAINT GREEN (-3400 4875);
DISPLAY INVISIBLE (-3400 4875);
FORCEPROP 1 LAST HDL_TAP TRUE
J 0
(-3075 4700);
DISPLAY 0.872340 (-3075 4700);
DISPLAY INVISIBLE (-3075 4700);
FORCEPROP 1 LAST PATH I477
J 0
(-3402 4825);
DISPLAY 0.872340 (-3402 4825);
PAINT GREEN (-3402 4825);
DISPLAY INVISIBLE (-3402 4825);
FORCEADD OFFPAGE..2
(-2800 4325);
FORCEPROP 2 LAST $XR0 10 
J 0
(-2611 4325);
DISPLAY 0.638298 (-2611 4325);
PAINT MONO (-2611 4325);
FORCEPROP 2 LAST CDS_LIB mstr_standard
J 0
(-2800 4325);
DISPLAY 0.723404 (-2800 4325);
PAINT MONO (-2800 4325);
DISPLAY INVISIBLE (-2800 4325);
FORCEPROP 1 LAST OFFPAGE TRUE
J 0
(-2475 4200);
DISPLAY 0.723404 (-2475 4200);
PAINT GREEN (-2475 4200);
DISPLAY INVISIBLE (-2475 4200);
FORCEPROP 1 LAST COMMENT_BODY TRUE
J 0
(-2845 4230);
DISPLAY 0.872340 (-2845 4230);
PAINT GREEN (-2845 4230);
DISPLAY INVISIBLE (-2845 4230);
FORCEPROP 2 LAST PATH I478
J 0
(-2500 4375);
DISPLAY 0.808511 (-2500 4375);
DISPLAY INVISIBLE (-2500 4375);
FORCEADD OFFPAGE..2
(-2800 4375);
FORCEPROP 2 LAST $XR0 10 
J 0
(-2611 4375);
DISPLAY 0.638298 (-2611 4375);
PAINT MONO (-2611 4375);
FORCEPROP 2 LAST CDS_LIB mstr_standard
J 0
(-2800 4375);
DISPLAY 0.723404 (-2800 4375);
PAINT MONO (-2800 4375);
DISPLAY INVISIBLE (-2800 4375);
FORCEPROP 1 LAST OFFPAGE TRUE
J 0
(-2475 4250);
DISPLAY 0.723404 (-2475 4250);
PAINT GREEN (-2475 4250);
DISPLAY INVISIBLE (-2475 4250);
FORCEPROP 1 LAST COMMENT_BODY TRUE
J 0
(-2845 4280);
DISPLAY 0.872340 (-2845 4280);
PAINT GREEN (-2845 4280);
DISPLAY INVISIBLE (-2845 4280);
FORCEPROP 2 LAST PATH I479
J 0
(-2500 4425);
DISPLAY 0.808511 (-2500 4425);
DISPLAY INVISIBLE (-2500 4425);
FORCEADD TAP..1
(-3600 4875);
FORCEPROP 3 LASTPIN (-3650 4875) SIG_NAME M_A_CPU0_SA_DQS_DP<4>
J 0
(-3640 4885);
DISPLAY 0.659574 (-3640 4885);
PAINT MONO (-3640 4885);
DISPLAY INVISIBLE (-3640 4885);
FORCEPROP 1 LASTPIN (-3650 4875) BN 4
J 0
(-3662 4883);
DISPLAY 0.489362 (-3662 4883);
PAINT GREEN (-3662 4883);
FORCEPROP 2 LAST CDS_LIB mstr_standard
J 0
(-3600 4875);
DISPLAY 0.723404 (-3600 4875);
PAINT MONO (-3600 4875);
DISPLAY INVISIBLE (-3600 4875);
FORCEPROP 1 LAST BODY_TYPE PLUMBING
J 0
(-3600 4925);
DISPLAY 0.872340 (-3600 4925);
PAINT GREEN (-3600 4925);
DISPLAY INVISIBLE (-3600 4925);
FORCEPROP 1 LAST HDL_TAP TRUE
J 0
(-3275 4750);
DISPLAY 0.872340 (-3275 4750);
DISPLAY INVISIBLE (-3275 4750);
FORCEPROP 1 LAST PATH I480
J 0
(-3602 4875);
DISPLAY 0.872340 (-3602 4875);
PAINT GREEN (-3602 4875);
DISPLAY INVISIBLE (-3602 4875);
FORCEADD TAP..1
(-3600 4975);
FORCEPROP 3 LASTPIN (-3650 4975) SIG_NAME M_A_CPU0_SA_DQS_DP<5>
J 0
(-3640 4985);
DISPLAY 0.659574 (-3640 4985);
PAINT MONO (-3640 4985);
DISPLAY INVISIBLE (-3640 4985);
FORCEPROP 1 LASTPIN (-3650 4975) BN 5
J 0
(-3662 4983);
DISPLAY 0.489362 (-3662 4983);
PAINT GREEN (-3662 4983);
FORCEPROP 2 LAST CDS_LIB mstr_standard
J 0
(-3600 4975);
DISPLAY 0.723404 (-3600 4975);
PAINT MONO (-3600 4975);
DISPLAY INVISIBLE (-3600 4975);
FORCEPROP 1 LAST BODY_TYPE PLUMBING
J 0
(-3600 5025);
DISPLAY 0.872340 (-3600 5025);
PAINT GREEN (-3600 5025);
DISPLAY INVISIBLE (-3600 5025);
FORCEPROP 1 LAST HDL_TAP TRUE
J 0
(-3275 4850);
DISPLAY 0.872340 (-3275 4850);
DISPLAY INVISIBLE (-3275 4850);
FORCEPROP 1 LAST PATH I481
J 0
(-3602 4975);
DISPLAY 0.872340 (-3602 4975);
PAINT GREEN (-3602 4975);
DISPLAY INVISIBLE (-3602 4975);
FORCEADD TAP..1
(-3600 5075);
FORCEPROP 3 LASTPIN (-3650 5075) SIG_NAME M_A_CPU0_SA_DQS_DP<6>
J 0
(-3640 5085);
DISPLAY 0.659574 (-3640 5085);
PAINT MONO (-3640 5085);
DISPLAY INVISIBLE (-3640 5085);
FORCEPROP 1 LASTPIN (-3650 5075) BN 6
J 0
(-3662 5083);
DISPLAY 0.489362 (-3662 5083);
PAINT GREEN (-3662 5083);
FORCEPROP 2 LAST CDS_LIB mstr_standard
J 0
(-3600 5075);
DISPLAY 0.723404 (-3600 5075);
PAINT MONO (-3600 5075);
DISPLAY INVISIBLE (-3600 5075);
FORCEPROP 1 LAST BODY_TYPE PLUMBING
J 0
(-3600 5125);
DISPLAY 0.872340 (-3600 5125);
PAINT GREEN (-3600 5125);
DISPLAY INVISIBLE (-3600 5125);
FORCEPROP 1 LAST HDL_TAP TRUE
J 0
(-3275 4950);
DISPLAY 0.872340 (-3275 4950);
DISPLAY INVISIBLE (-3275 4950);
FORCEPROP 1 LAST PATH I482
J 0
(-3602 5075);
DISPLAY 0.872340 (-3602 5075);
PAINT GREEN (-3602 5075);
DISPLAY INVISIBLE (-3602 5075);
FORCEADD TAP..1
(-3400 5125);
FORCEPROP 3 LASTPIN (-3450 5125) SIG_NAME M_A_CPU0_SA_DQS_DN<7>
J 0
(-3440 5135);
DISPLAY 0.659574 (-3440 5135);
PAINT MONO (-3440 5135);
DISPLAY INVISIBLE (-3440 5135);
FORCEPROP 1 LASTPIN (-3450 5125) BN 7
J 0
(-3462 5133);
DISPLAY 0.489362 (-3462 5133);
PAINT GREEN (-3462 5133);
FORCEPROP 2 LAST CDS_LIB mstr_standard
J 0
(-3400 5125);
DISPLAY 0.723404 (-3400 5125);
PAINT MONO (-3400 5125);
DISPLAY INVISIBLE (-3400 5125);
FORCEPROP 1 LAST BODY_TYPE PLUMBING
J 0
(-3400 5175);
DISPLAY 0.872340 (-3400 5175);
PAINT GREEN (-3400 5175);
DISPLAY INVISIBLE (-3400 5175);
FORCEPROP 1 LAST HDL_TAP TRUE
J 0
(-3075 5000);
DISPLAY 0.872340 (-3075 5000);
DISPLAY INVISIBLE (-3075 5000);
FORCEPROP 1 LAST PATH I483
J 0
(-3402 5125);
DISPLAY 0.872340 (-3402 5125);
PAINT GREEN (-3402 5125);
DISPLAY INVISIBLE (-3402 5125);
FORCEADD TAP..1
(-3400 5025);
FORCEPROP 3 LASTPIN (-3450 5025) SIG_NAME M_A_CPU0_SA_DQS_DN<6>
J 0
(-3440 5035);
DISPLAY 0.659574 (-3440 5035);
PAINT MONO (-3440 5035);
DISPLAY INVISIBLE (-3440 5035);
FORCEPROP 1 LASTPIN (-3450 5025) BN 6
J 0
(-3462 5033);
DISPLAY 0.489362 (-3462 5033);
PAINT GREEN (-3462 5033);
FORCEPROP 2 LAST CDS_LIB mstr_standard
J 0
(-3400 5025);
DISPLAY 0.723404 (-3400 5025);
PAINT MONO (-3400 5025);
DISPLAY INVISIBLE (-3400 5025);
FORCEPROP 1 LAST BODY_TYPE PLUMBING
J 0
(-3400 5075);
DISPLAY 0.872340 (-3400 5075);
PAINT GREEN (-3400 5075);
DISPLAY INVISIBLE (-3400 5075);
FORCEPROP 1 LAST HDL_TAP TRUE
J 0
(-3075 4900);
DISPLAY 0.872340 (-3075 4900);
DISPLAY INVISIBLE (-3075 4900);
FORCEPROP 1 LAST PATH I484
J 0
(-3402 5025);
DISPLAY 0.872340 (-3402 5025);
PAINT GREEN (-3402 5025);
DISPLAY INVISIBLE (-3402 5025);
FORCEADD TAP..1
(-3400 4925);
FORCEPROP 3 LASTPIN (-3450 4925) SIG_NAME M_A_CPU0_SA_DQS_DN<5>
J 0
(-3440 4935);
DISPLAY 0.659574 (-3440 4935);
PAINT MONO (-3440 4935);
DISPLAY INVISIBLE (-3440 4935);
FORCEPROP 1 LASTPIN (-3450 4925) BN 5
J 0
(-3462 4933);
DISPLAY 0.489362 (-3462 4933);
PAINT GREEN (-3462 4933);
FORCEPROP 2 LAST CDS_LIB mstr_standard
J 0
(-3400 4925);
DISPLAY 0.723404 (-3400 4925);
PAINT MONO (-3400 4925);
DISPLAY INVISIBLE (-3400 4925);
FORCEPROP 1 LAST BODY_TYPE PLUMBING
J 0
(-3400 4975);
DISPLAY 0.872340 (-3400 4975);
PAINT GREEN (-3400 4975);
DISPLAY INVISIBLE (-3400 4975);
FORCEPROP 1 LAST HDL_TAP TRUE
J 0
(-3075 4800);
DISPLAY 0.872340 (-3075 4800);
DISPLAY INVISIBLE (-3075 4800);
FORCEPROP 1 LAST PATH I485
J 0
(-3402 4925);
DISPLAY 0.872340 (-3402 4925);
PAINT GREEN (-3402 4925);
DISPLAY INVISIBLE (-3402 4925);
FORCEADD TAP..1
(-3600 5175);
FORCEPROP 3 LASTPIN (-3650 5175) SIG_NAME M_A_CPU0_SA_DQS_DP<7>
J 0
(-3640 5185);
DISPLAY 0.659574 (-3640 5185);
PAINT MONO (-3640 5185);
DISPLAY INVISIBLE (-3640 5185);
FORCEPROP 1 LASTPIN (-3650 5175) BN 7
J 0
(-3662 5183);
DISPLAY 0.489362 (-3662 5183);
PAINT GREEN (-3662 5183);
FORCEPROP 2 LAST CDS_LIB mstr_standard
J 0
(-3600 5175);
DISPLAY 0.723404 (-3600 5175);
PAINT MONO (-3600 5175);
DISPLAY INVISIBLE (-3600 5175);
FORCEPROP 1 LAST BODY_TYPE PLUMBING
J 0
(-3600 5225);
DISPLAY 0.872340 (-3600 5225);
PAINT GREEN (-3600 5225);
DISPLAY INVISIBLE (-3600 5225);
FORCEPROP 1 LAST HDL_TAP TRUE
J 0
(-3275 5050);
DISPLAY 0.872340 (-3275 5050);
DISPLAY INVISIBLE (-3275 5050);
FORCEPROP 1 LAST PATH I486
J 0
(-3602 5175);
DISPLAY 0.872340 (-3602 5175);
PAINT GREEN (-3602 5175);
DISPLAY INVISIBLE (-3602 5175);
FORCEADD TAP..1
(-3600 5275);
FORCEPROP 3 LASTPIN (-3650 5275) SIG_NAME M_A_CPU0_SA_DQS_DP<8>
J 0
(-3640 5285);
DISPLAY 0.659574 (-3640 5285);
PAINT MONO (-3640 5285);
DISPLAY INVISIBLE (-3640 5285);
FORCEPROP 1 LASTPIN (-3650 5275) BN 8
J 0
(-3662 5283);
DISPLAY 0.489362 (-3662 5283);
PAINT GREEN (-3662 5283);
FORCEPROP 2 LAST CDS_LIB mstr_standard
J 0
(-3600 5275);
DISPLAY 0.723404 (-3600 5275);
PAINT MONO (-3600 5275);
DISPLAY INVISIBLE (-3600 5275);
FORCEPROP 1 LAST BODY_TYPE PLUMBING
J 0
(-3600 5325);
DISPLAY 0.872340 (-3600 5325);
PAINT GREEN (-3600 5325);
DISPLAY INVISIBLE (-3600 5325);
FORCEPROP 1 LAST HDL_TAP TRUE
J 0
(-3275 5150);
DISPLAY 0.872340 (-3275 5150);
DISPLAY INVISIBLE (-3275 5150);
FORCEPROP 1 LAST PATH I487
J 0
(-3602 5275);
DISPLAY 0.872340 (-3602 5275);
PAINT GREEN (-3602 5275);
DISPLAY INVISIBLE (-3602 5275);
FORCEADD TAP..1
(-3600 5375);
FORCEPROP 3 LASTPIN (-3650 5375) SIG_NAME M_A_CPU0_SA_DQS_DP<9>
J 0
(-3640 5385);
DISPLAY 0.659574 (-3640 5385);
PAINT MONO (-3640 5385);
DISPLAY INVISIBLE (-3640 5385);
FORCEPROP 1 LASTPIN (-3650 5375) BN 9
J 0
(-3662 5383);
DISPLAY 0.489362 (-3662 5383);
PAINT GREEN (-3662 5383);
FORCEPROP 2 LAST CDS_LIB mstr_standard
J 0
(-3600 5375);
DISPLAY 0.723404 (-3600 5375);
PAINT MONO (-3600 5375);
DISPLAY INVISIBLE (-3600 5375);
FORCEPROP 1 LAST BODY_TYPE PLUMBING
J 0
(-3600 5425);
DISPLAY 0.872340 (-3600 5425);
PAINT GREEN (-3600 5425);
DISPLAY INVISIBLE (-3600 5425);
FORCEPROP 1 LAST HDL_TAP TRUE
J 0
(-3275 5250);
DISPLAY 0.872340 (-3275 5250);
DISPLAY INVISIBLE (-3275 5250);
FORCEPROP 1 LAST PATH I488
J 0
(-3602 5375);
DISPLAY 0.872340 (-3602 5375);
PAINT GREEN (-3602 5375);
DISPLAY INVISIBLE (-3602 5375);
FORCEADD TAP..1
(-3400 5325);
FORCEPROP 3 LASTPIN (-3450 5325) SIG_NAME M_A_CPU0_SA_DQS_DN<9>
J 0
(-3440 5335);
DISPLAY 0.659574 (-3440 5335);
PAINT MONO (-3440 5335);
DISPLAY INVISIBLE (-3440 5335);
FORCEPROP 1 LASTPIN (-3450 5325) BN 9
J 0
(-3462 5333);
DISPLAY 0.489362 (-3462 5333);
PAINT GREEN (-3462 5333);
FORCEPROP 2 LAST CDS_LIB mstr_standard
J 0
(-3400 5325);
DISPLAY 0.723404 (-3400 5325);
PAINT MONO (-3400 5325);
DISPLAY INVISIBLE (-3400 5325);
FORCEPROP 1 LAST BODY_TYPE PLUMBING
J 0
(-3400 5375);
DISPLAY 0.872340 (-3400 5375);
PAINT GREEN (-3400 5375);
DISPLAY INVISIBLE (-3400 5375);
FORCEPROP 1 LAST HDL_TAP TRUE
J 0
(-3075 5200);
DISPLAY 0.872340 (-3075 5200);
DISPLAY INVISIBLE (-3075 5200);
FORCEPROP 1 LAST PATH I489
J 0
(-3402 5325);
DISPLAY 0.872340 (-3402 5325);
PAINT GREEN (-3402 5325);
DISPLAY INVISIBLE (-3402 5325);
FORCEADD TAP..1
(-3400 5225);
FORCEPROP 3 LASTPIN (-3450 5225) SIG_NAME M_A_CPU0_SA_DQS_DN<8>
J 0
(-3440 5235);
DISPLAY 0.659574 (-3440 5235);
PAINT MONO (-3440 5235);
DISPLAY INVISIBLE (-3440 5235);
FORCEPROP 1 LASTPIN (-3450 5225) BN 8
J 0
(-3462 5233);
DISPLAY 0.489362 (-3462 5233);
PAINT GREEN (-3462 5233);
FORCEPROP 2 LAST CDS_LIB mstr_standard
J 0
(-3400 5225);
DISPLAY 0.723404 (-3400 5225);
PAINT MONO (-3400 5225);
DISPLAY INVISIBLE (-3400 5225);
FORCEPROP 1 LAST BODY_TYPE PLUMBING
J 0
(-3400 5275);
DISPLAY 0.872340 (-3400 5275);
PAINT GREEN (-3400 5275);
DISPLAY INVISIBLE (-3400 5275);
FORCEPROP 1 LAST HDL_TAP TRUE
J 0
(-3075 5100);
DISPLAY 0.872340 (-3075 5100);
DISPLAY INVISIBLE (-3075 5100);
FORCEPROP 1 LAST PATH I490
J 0
(-3402 5225);
DISPLAY 0.872340 (-3402 5225);
PAINT GREEN (-3402 5225);
DISPLAY INVISIBLE (-3402 5225);
FORCEADD OFFPAGE..2
(-2800 5375);
FORCEPROP 2 LAST $XR0 10 
J 0
(-2611 5375);
DISPLAY 0.638298 (-2611 5375);
PAINT MONO (-2611 5375);
FORCEPROP 2 LAST CDS_LIB mstr_standard
J 0
(-2800 5375);
DISPLAY 0.723404 (-2800 5375);
PAINT MONO (-2800 5375);
DISPLAY INVISIBLE (-2800 5375);
FORCEPROP 1 LAST OFFPAGE TRUE
J 0
(-2475 5250);
DISPLAY 0.723404 (-2475 5250);
PAINT GREEN (-2475 5250);
DISPLAY INVISIBLE (-2475 5250);
FORCEPROP 1 LAST COMMENT_BODY TRUE
J 0
(-2845 5280);
DISPLAY 0.872340 (-2845 5280);
PAINT GREEN (-2845 5280);
DISPLAY INVISIBLE (-2845 5280);
FORCEPROP 2 LAST PATH I491
J 0
(-2500 5425);
DISPLAY 0.808511 (-2500 5425);
DISPLAY INVISIBLE (-2500 5425);
FORCEADD OFFPAGE..2
(-2800 5425);
FORCEPROP 2 LAST $XR0 10 
J 0
(-2611 5425);
DISPLAY 0.638298 (-2611 5425);
PAINT MONO (-2611 5425);
FORCEPROP 2 LAST CDS_LIB mstr_standard
J 0
(-2800 5425);
DISPLAY 0.723404 (-2800 5425);
PAINT MONO (-2800 5425);
DISPLAY INVISIBLE (-2800 5425);
FORCEPROP 1 LAST OFFPAGE TRUE
J 0
(-2475 5300);
DISPLAY 0.723404 (-2475 5300);
PAINT GREEN (-2475 5300);
DISPLAY INVISIBLE (-2475 5300);
FORCEPROP 1 LAST COMMENT_BODY TRUE
J 0
(-2845 5330);
DISPLAY 0.872340 (-2845 5330);
PAINT GREEN (-2845 5330);
DISPLAY INVISIBLE (-2845 5330);
FORCEPROP 2 LAST PATH I492
J 0
(-2500 5475);
DISPLAY 0.808511 (-2500 5475);
DISPLAY INVISIBLE (-2500 5475);
FORCEADD VCC_CORE..1
(-8875 3525);
FORCEPROP 3 LASTPIN (-8875 3475) SIG_NAME P3V3_AUX\g
J 0
(-8865 3485);
DISPLAY 0.659574 (-8865 3485);
PAINT MONO (-8865 3485);
DISPLAY INVISIBLE (-8865 3485);
FORCEPROP 1 LAST HDL_POWER P3V3_AUX
J 1
(-8875 3575);
DISPLAY 0.489362 (-8875 3575);
PAINT GREEN (-8875 3575);
FORCEPROP 2 LAST ROOM PVCCINFAON_CPU0_CTRL
J 0
(-8875 3625);
DISPLAY 0.808511 (-8875 3625);
PAINT RED (-8875 3625);
DISPLAY INVISIBLE (-8875 3625);
FORCEPROP 0 LAST VOLTAGE 3.3
J 0
(-9150 3675);
DISPLAY 1.021277 (-9150 3675);
PAINT SKYBLUE (-9150 3675);
DISPLAY INVISIBLE (-9150 3675);
FORCEPROP 2 LAST CDS_LIB mstr_symbols
J 0
(-8875 3525);
PAINT MONO (-8875 3525);
DISPLAY INVISIBLE (-8875 3525);
FORCEPROP 1 LAST PATH I493
J 0
(-8825 3550);
DISPLAY 0.872340 (-8825 3550);
PAINT GREEN (-8825 3550);
DISPLAY INVISIBLE (-8825 3550);
FORCEADD OFFPAGE..1
(-9100 2925);
FORCEPROP 2 LAST $XR0 86 
J 0
(-9321 2925);
DISPLAY 0.638298 (-9321 2925);
PAINT MONO (-9321 2925);
FORCEPROP 2 LAST CDS_LIB mstr_standard
J 0
(-9100 2925);
DISPLAY 0.808511 (-9100 2925);
DISPLAY INVISIBLE (-9100 2925);
FORCEPROP 1 LAST OFFPAGE TRUE
J 0
(-8775 2800);
DISPLAY 0.872340 (-8775 2800);
PAINT GREEN (-8775 2800);
DISPLAY INVISIBLE (-8775 2800);
FORCEPROP 1 LAST COMMENT_BODY TRUE
J 0
(-8975 2825);
DISPLAY 0.872340 (-8975 2825);
PAINT GREEN (-8975 2825);
DISPLAY INVISIBLE (-8975 2825);
FORCEPROP 2 LAST PATH I495
J 0
(-9050 3000);
DISPLAY 0.808511 (-9050 3000);
DISPLAY INVISIBLE (-9050 3000);
FORCEADD OFFPAGE..1
(-8400 2700);
FORCEPROP 2 LASTPIN (-8350 2700) SIG_NAME I3C_SPD_DDRAF_CPU0_SCL
J 0
(-8360 2710);
DISPLAY 0.446809 (-8360 2710);
FORCEPROP 2 LAST $XR5 91 
J 0
(-9102 2700);
DISPLAY 0.638298 (-9102 2700);
PAINT MONO (-9102 2700);
FORCEPROP 2 LAST $XR4 90 
J 0
(-9012 2700);
DISPLAY 0.638298 (-9012 2700);
PAINT MONO (-9012 2700);
FORCEPROP 2 LAST $XR3 89 
J 0
(-8922 2700);
DISPLAY 0.638298 (-8922 2700);
PAINT MONO (-8922 2700);
FORCEPROP 2 LAST $XR2 88 
J 0
(-8832 2700);
DISPLAY 0.638298 (-8832 2700);
PAINT MONO (-8832 2700);
FORCEPROP 2 LAST $XR1 87 
J 0
(-8742 2700);
DISPLAY 0.638298 (-8742 2700);
PAINT MONO (-8742 2700);
FORCEPROP 2 LAST $XR0 159 
J 0
(-8652 2700);
DISPLAY 0.638298 (-8652 2700);
PAINT MONO (-8652 2700);
FORCEPROP 2 LAST CDS_LIB mstr_standard
J 0
(-8400 2700);
DISPLAY 0.808511 (-8400 2700);
DISPLAY INVISIBLE (-8400 2700);
FORCEPROP 1 LAST OFFPAGE TRUE
J 0
(-8075 2575);
DISPLAY 0.872340 (-8075 2575);
PAINT GREEN (-8075 2575);
DISPLAY INVISIBLE (-8075 2575);
FORCEPROP 1 LAST COMMENT_BODY TRUE
J 0
(-8275 2600);
DISPLAY 0.872340 (-8275 2600);
PAINT GREEN (-8275 2600);
DISPLAY INVISIBLE (-8275 2600);
FORCEPROP 2 LAST PATH I496
J 0
(-8825 2750);
DISPLAY 0.808511 (-8825 2750);
DISPLAY INVISIBLE (-8825 2750);
FORCEADD OFFPAGE..5
(-7275 1500);
FORCEPROP 2 LAST $XR0 86 
J 0
(-7529 1500);
DISPLAY 0.638298 (-7529 1500);
PAINT MONO (-7529 1500);
FORCEPROP 2 LAST CDS_LIB mstr_standard
J 0
(-7275 1500);
DISPLAY 0.808511 (-7275 1500);
DISPLAY INVISIBLE (-7275 1500);
FORCEPROP 2 LAST BOM_COST MEM
J 0
(-7350 1575);
DISPLAY 0.808511 (-7350 1575);
DISPLAY INVISIBLE (-7350 1575);
FORCEPROP 1 LAST OFFPAGE TRUE
J 0
(-6950 1375);
DISPLAY 0.872340 (-6950 1375);
PAINT GREEN (-6950 1375);
DISPLAY INVISIBLE (-6950 1375);
FORCEPROP 1 LAST COMMENT_BODY TRUE
J 0
(-7175 1425);
DISPLAY 0.872340 (-7175 1425);
PAINT GREEN (-7175 1425);
DISPLAY INVISIBLE (-7175 1425);
FORCEPROP 2 LAST PATH I497
J 0
(-7225 1575);
DISPLAY 0.808511 (-7225 1575);
DISPLAY INVISIBLE (-7225 1575);
FORCEADD GND..1
(-6500 1100);
FORCEPROP 3 LASTPIN (-6500 1150) SIG_NAME GND\g
J 0
(-6490 1160);
DISPLAY 0.659574 (-6490 1160);
PAINT MONO (-6490 1160);
DISPLAY INVISIBLE (-6490 1160);
FORCEPROP 1 LAST VOLTAGE 0.0
J 0
(-6545 1057);
DISPLAY 0.723404 (-6545 1057);
PAINT SKYBLUE (-6545 1057);
DISPLAY INVISIBLE (-6545 1057);
FORCEPROP 1 LAST SIZE 1B
J 0
(-6425 1050);
DISPLAY 0.851064 (-6425 1050);
PAINT GREEN (-6425 1050);
DISPLAY INVISIBLE (-6425 1050);
FORCEPROP 2 LAST CDS_LIB mstr_symbols
J 0
(-6500 1100);
DISPLAY 0.808511 (-6500 1100);
DISPLAY INVISIBLE (-6500 1100);
FORCEPROP 2 LAST BOM_COST MEM
J 0
(-6600 1175);
DISPLAY 0.808511 (-6600 1175);
DISPLAY INVISIBLE (-6600 1175);
FORCEPROP 1 LAST BODY_TYPE PLUMBING
J 0
(-6545 1057);
DISPLAY 0.340426 (-6545 1057);
PAINT GREEN (-6545 1057);
DISPLAY INVISIBLE (-6545 1057);
FORCEPROP 1 LAST HDL_POWER GND
J 0
(-6500 1250);
DISPLAY 0.851064 (-6500 1250);
PAINT GREEN (-6500 1250);
DISPLAY INVISIBLE (-6500 1250);
FORCEPROP 1 LAST PATH I498
J 0
(-6425 1100);
DISPLAY 0.872340 (-6425 1100);
PAINT GREEN (-6425 1100);
DISPLAY INVISIBLE (-6425 1100);
FORCEADD Q_RES..2
(-6500 1325);
FORCEPROP 1 LAST LOCATION R7
J 0
(-6455 1450);
DISPLAY 0.489362 (-6455 1450);
PAINT SKYBLUE (-6455 1450);
FORCEPROP 2 LAST SEC 1
J 0
(-6450 1550);
DISPLAY 0.808511 (-6450 1550);
PAINT MONO (-6450 1550);
DISPLAY INVISIBLE (-6450 1550);
FORCEPROP 1 LASTPIN (-6500 1425) $PN 1
J 0
(-6495 1387);
DISPLAY 0.489362 (-6495 1387);
PAINT WHITE (-6495 1387);
FORCEPROP 1 LASTPIN (-6500 1225) $PN 2
J 0
(-6495 1235);
DISPLAY 0.489362 (-6495 1235);
PAINT WHITE (-6495 1235);
FORCEPROP 0 LASTPIN (-6500 1425) XNET_PINS 3
R 1
J 0
(-6510 1435);
DISPLAY 0.808511 (-6510 1435);
PAINT MONO (-6510 1435);
DISPLAY INVISIBLE (-6510 1435);
FORCEPROP 0 LASTPIN (-6500 1225) XNET_PINS 2
R 1
J 2
(-6510 1215);
DISPLAY 0.808511 (-6510 1215);
PAINT MONO (-6510 1215);
DISPLAY INVISIBLE (-6510 1215);
FORCEPROP 1 LAST TOLERANCE 1%
J 0
(-6455 1350);
DISPLAY 0.489362 (-6455 1350);
PAINT SKYBLUE (-6455 1350);
FORCEPROP 1 LAST VALUE 10K
J 0
(-6455 1400);
DISPLAY 0.489362 (-6455 1400);
PAINT SKYBLUE (-6455 1400);
FORCEPROP 1 LAST PACK_TYPE 0402LF
J 0
(-6460 1150);
DISPLAY 0.489362 (-6460 1150);
PAINT SKYBLUE (-6460 1150);
FORCEPROP 1 LAST WATTAGE 1/16W
J 0
(-6460 1300);
DISPLAY 0.489362 (-6460 1300);
PAINT SKYBLUE (-6460 1300);
FORCEPROP 1 LAST MATERIAL CHIP
J 0
(-6460 1250);
DISPLAY 0.489362 (-6460 1250);
PAINT SKYBLUE (-6460 1250);
FORCEPROP 2 LAST ROOM 
J 0
(-6450 1550);
DISPLAY 0.808511 (-6450 1550);
PAINT RED (-6450 1550);
DISPLAY INVISIBLE (-6450 1550);
FORCEPROP 2 LAST CDS_LIB pure_quanta
J 0
(-6500 1325);
DISPLAY INVISIBLE (-6500 1325);
FORCEPROP 2 LAST SEC_TYPE 0402LF
J 0
(-6450 1550);
DISPLAY 0.808511 (-6450 1550);
PAINT MONO (-6450 1550);
DISPLAY INVISIBLE (-6450 1550);
FORCEPROP 2 LAST BOM_COST MEM
J 0
(-6450 1500);
DISPLAY 0.808511 (-6450 1500);
DISPLAY INVISIBLE (-6450 1500);
FORCEPROP 1 LAST PATH I499
J 0
(-6450 1500);
DISPLAY 0.978723 (-6450 1500);
PAINT WHITE (-6450 1500);
DISPLAY INVISIBLE (-6450 1500);
FORCEPROP 1 LAST PART_NUMBER CS31002FB08
J 0
(-6460 1200);
DISPLAY 0.489362 (-6460 1200);
PAINT SKYBLUE (-6460 1200);
DISPLAY INVISIBLE (-6460 1200);
FORCEADD OFFPAGE..6
(-9075 2250);
FORCEPROP 2 LAST $XR5 91 
J 0
(-9414 2286);
DISPLAY 0.638298 (-9414 2286);
PAINT MONO (-9414 2286);
FORCEPROP 2 LAST $XR4 90 
J 0
(-9324 2286);
DISPLAY 0.638298 (-9324 2286);
PAINT MONO (-9324 2286);
FORCEPROP 2 LAST $XR3 89 
J 0
(-9414 2214);
DISPLAY 0.638298 (-9414 2214);
PAINT MONO (-9414 2214);
FORCEPROP 2 LAST $XR2 88 
J 0
(-9324 2214);
DISPLAY 0.638298 (-9324 2214);
PAINT MONO (-9324 2214);
FORCEPROP 2 LAST $XR1 87 
J 0
(-9414 2250);
DISPLAY 0.638298 (-9414 2250);
PAINT MONO (-9414 2250);
FORCEPROP 2 LAST $XR0 86 
J 0
(-9324 2250);
DISPLAY 0.638298 (-9324 2250);
PAINT MONO (-9324 2250);
FORCEPROP 2 LAST CDS_LIB mstr_standard
J 0
(-9075 2250);
DISPLAY 0.808511 (-9075 2250);
DISPLAY INVISIBLE (-9075 2250);
FORCEPROP 1 LAST OFFPAGE TRUE
J 0
(-8750 2125);
DISPLAY 0.872340 (-8750 2125);
PAINT GREEN (-8750 2125);
DISPLAY INVISIBLE (-8750 2125);
FORCEPROP 1 LAST COMMENT_BODY TRUE
J 0
(-8975 2175);
DISPLAY 0.872340 (-8975 2175);
PAINT GREEN (-8975 2175);
DISPLAY INVISIBLE (-8975 2175);
FORCEPROP 2 LAST PATH I509
J 0
(-9025 2325);
DISPLAY 0.808511 (-9025 2325);
DISPLAY INVISIBLE (-9025 2325);
FORCEADD OFFPAGE..5
(-8350 3075);
FORCEPROP 2 LAST $XR0 10 
J 0
(-8574 3075);
DISPLAY 0.638298 (-8574 3075);
PAINT MONO (-8574 3075);
FORCEPROP 2 LAST CDS_LIB mstr_standard
J 0
(-8350 3075);
DISPLAY INVISIBLE (-8350 3075);
FORCEPROP 1 LAST OFFPAGE TRUE
J 0
(-8025 2950);
DISPLAY 0.872340 (-8025 2950);
PAINT GREEN (-8025 2950);
DISPLAY INVISIBLE (-8025 2950);
FORCEPROP 1 LAST COMMENT_BODY TRUE
J 0
(-8250 3000);
DISPLAY 0.872340 (-8250 3000);
PAINT GREEN (-8250 3000);
DISPLAY INVISIBLE (-8250 3000);
FORCEPROP 2 LAST PATH I518
J 0
(-8300 3150);
DISPLAY 1.021277 (-8300 3150);
DISPLAY INVISIBLE (-8300 3150);
FORCEADD Q_CAP..1
R 2
(-2950 6050);
FORCEPROP 1 LAST LOCATION C89
J 2
(-3000 6150);
DISPLAY 0.489362 (-3000 6150);
PAINT SKYBLUE (-3000 6150);
FORCEPROP 0 LAST $SEC 1
J 0
(-3000 6200);
DISPLAY 0.680851 (-3000 6200);
PAINT MONO (-3000 6200);
DISPLAY INVISIBLE (-3000 6200);
FORCEPROP 0 LAST CDS_SEC 1
J 0
(-3000 6200);
DISPLAY 1.021277 (-3000 6200);
DISPLAY INVISIBLE (-3000 6200);
FORCEPROP 1 LASTPIN (-2950 6150) $PN 1
J 2
(-2960 6130);
DISPLAY 0.489362 (-2960 6130);
PAINT MONO (-2960 6130);
FORCEPROP 1 LASTPIN (-2950 5950) $PN 2
J 2
(-2960 5930);
DISPLAY 0.489362 (-2960 5930);
PAINT MONO (-2960 5930);
FORCEPROP 1 LAST TOLERANCE 10%
J 2
(-3000 6000);
DISPLAY 0.489362 (-3000 6000);
PAINT SKYBLUE (-3000 6000);
FORCEPROP 1 LAST VALUE 10UF
J 2
(-3000 6100);
DISPLAY 0.489362 (-3000 6100);
PAINT SKYBLUE (-3000 6100);
FORCEPROP 1 LAST VOLTAGE 25V
J 2
(-3000 6050);
DISPLAY 0.489362 (-3000 6050);
PAINT SKYBLUE (-3000 6050);
FORCEPROP 1 LAST PACK_TYPE C0805
J 2
(-3000 5850);
DISPLAY 0.489362 (-3000 5850);
PAINT SKYBLUE (-3000 5850);
FORCEPROP 1 LAST MATERIAL X6S
J 2
(-3000 5950);
DISPLAY 0.489362 (-3000 5950);
PAINT SKYBLUE (-3000 5950);
FORCEPROP 2 LAST ROOM 
J 2
(-3005 6195);
DISPLAY 0.595745 (-3005 6195);
PAINT RED (-3005 6195);
DISPLAY INVISIBLE (-3005 6195);
FORCEPROP 2 LAST CDS_LIB pure_quanta
J 0
(-2950 6050);
DISPLAY INVISIBLE (-2950 6050);
FORCEPROP 0 LAST BOM_COST MEM
J 2
(-3005 6195);
DISPLAY 0.595745 (-3005 6195);
PAINT MONO (-3005 6195);
DISPLAY INVISIBLE (-3005 6195);
FORCEPROP 1 LAST PATH I519
J 2
(-3000 6200);
DISPLAY 0.978723 (-3000 6200);
PAINT WHITE (-3000 6200);
DISPLAY INVISIBLE (-3000 6200);
FORCEPROP 1 LAST PART_NUMBER CH6104KEA00
J 2
(-3000 5900);
DISPLAY 0.489362 (-3000 5900);
PAINT SKYBLUE (-3000 5900);
DISPLAY INVISIBLE (-3000 5900);
FORCEADD GND..1
(-2950 5700);
FORCEPROP 3 LASTPIN (-2950 5750) SIG_NAME GND\g
J 0
(-2940 5760);
DISPLAY 0.659574 (-2940 5760);
PAINT MONO (-2940 5760);
DISPLAY INVISIBLE (-2940 5760);
FORCEPROP 2 LAST ROOM MEM_EFGH_DECOUPLING_CAPS
J 0
(-2925 5775);
DISPLAY 0.659574 (-2925 5775);
PAINT RED (-2925 5775);
DISPLAY INVISIBLE (-2925 5775);
FORCEPROP 1 LAST VOLTAGE 0
J 0
(-2970 5795);
DISPLAY 0.829787 (-2970 5795);
PAINT SKYBLUE (-2970 5795);
DISPLAY INVISIBLE (-2970 5795);
FORCEPROP 2 LAST CDS_LIB mstr_symbols
J 0
(-2950 5700);
DISPLAY 0.808511 (-2950 5700);
DISPLAY INVISIBLE (-2950 5700);
FORCEPROP 1 LAST SIZE 1B
J 0
(-2875 5650);
DISPLAY 0.723404 (-2875 5650);
PAINT GREEN (-2875 5650);
DISPLAY INVISIBLE (-2875 5650);
FORCEPROP 2 LAST BOM_COST MEM
J 0
(-2925 5825);
DISPLAY 0.659574 (-2925 5825);
DISPLAY INVISIBLE (-2925 5825);
FORCEPROP 1 LAST BODY_TYPE PLUMBING
J 0
(-2995 5657);
DISPLAY 0.276596 (-2995 5657);
PAINT GREEN (-2995 5657);
DISPLAY INVISIBLE (-2995 5657);
FORCEPROP 1 LAST HDL_POWER GND
J 0
(-2950 5850);
DISPLAY 0.723404 (-2950 5850);
PAINT GREEN (-2950 5850);
DISPLAY INVISIBLE (-2950 5850);
FORCEPROP 1 LAST PATH I522
J 0
(-2875 5700);
DISPLAY 0.872340 (-2875 5700);
PAINT AQUA (-2875 5700);
DISPLAY INVISIBLE (-2875 5700);
FORCEADD Q_CAP..1
R 2
(-9000 3225);
FORCEPROP 1 LAST LOCATION C88
J 2
(-9050 3325);
DISPLAY 0.489362 (-9050 3325);
PAINT SKYBLUE (-9050 3325);
FORCEPROP 0 LAST $SEC 1
J 0
(-9050 3375);
DISPLAY 0.680851 (-9050 3375);
PAINT MONO (-9050 3375);
DISPLAY INVISIBLE (-9050 3375);
FORCEPROP 0 LAST CDS_SEC 1
J 0
(-9050 3375);
DISPLAY 1.021277 (-9050 3375);
DISPLAY INVISIBLE (-9050 3375);
FORCEPROP 1 LASTPIN (-9000 3325) $PN 1
J 2
(-9010 3305);
DISPLAY 0.489362 (-9010 3305);
PAINT MONO (-9010 3305);
FORCEPROP 1 LASTPIN (-9000 3125) $PN 2
J 2
(-9010 3105);
DISPLAY 0.489362 (-9010 3105);
PAINT MONO (-9010 3105);
FORCEPROP 1 LAST MATERIAL X7R
J 2
(-9050 3125);
DISPLAY 0.489362 (-9050 3125);
PAINT SKYBLUE (-9050 3125);
FORCEPROP 1 LAST TOLERANCE 10%
J 2
(-9050 3175);
DISPLAY 0.489362 (-9050 3175);
PAINT SKYBLUE (-9050 3175);
FORCEPROP 1 LAST PACK_TYPE 0402
J 2
(-9050 3025);
DISPLAY 0.489362 (-9050 3025);
PAINT SKYBLUE (-9050 3025);
FORCEPROP 1 LAST VOLTAGE 25V
J 2
(-9050 3225);
DISPLAY 0.489362 (-9050 3225);
PAINT SKYBLUE (-9050 3225);
FORCEPROP 1 LAST VALUE 0.1UF
J 2
(-9050 3275);
DISPLAY 0.489362 (-9050 3275);
PAINT SKYBLUE (-9050 3275);
FORCEPROP 2 LAST CDS_LIB pure_quanta
J 0
(-9000 3225);
DISPLAY INVISIBLE (-9000 3225);
FORCEPROP 0 LAST BOM_COST MEM
J 2
(-9055 3370);
DISPLAY 0.595745 (-9055 3370);
PAINT MONO (-9055 3370);
DISPLAY INVISIBLE (-9055 3370);
FORCEPROP 1 LAST PATH I523
J 2
(-9050 3375);
DISPLAY 0.978723 (-9050 3375);
PAINT WHITE (-9050 3375);
DISPLAY INVISIBLE (-9050 3375);
FORCEPROP 1 LAST PART_NUMBER CH4104K1B00
J 2
(-9050 3075);
DISPLAY 0.489362 (-9050 3075);
PAINT SKYBLUE (-9050 3075);
DISPLAY INVISIBLE (-9050 3075);
FORCEADD GND..1
(-9000 3000);
FORCEPROP 3 LASTPIN (-9000 3050) SIG_NAME GND\g
J 0
(-8990 3060);
DISPLAY 0.659574 (-8990 3060);
PAINT MONO (-8990 3060);
DISPLAY INVISIBLE (-8990 3060);
FORCEPROP 2 LAST ROOM MEM_EFGH_DECOUPLING_CAPS
J 0
(-8975 3075);
DISPLAY 0.659574 (-8975 3075);
PAINT RED (-8975 3075);
DISPLAY INVISIBLE (-8975 3075);
FORCEPROP 1 LAST VOLTAGE 0
J 0
(-9020 3095);
DISPLAY 0.829787 (-9020 3095);
PAINT SKYBLUE (-9020 3095);
DISPLAY INVISIBLE (-9020 3095);
FORCEPROP 2 LAST CDS_LIB mstr_symbols
J 0
(-9000 3000);
DISPLAY 0.808511 (-9000 3000);
DISPLAY INVISIBLE (-9000 3000);
FORCEPROP 1 LAST SIZE 1B
J 0
(-8925 2950);
DISPLAY 0.723404 (-8925 2950);
PAINT GREEN (-8925 2950);
DISPLAY INVISIBLE (-8925 2950);
FORCEPROP 2 LAST BOM_COST MEM
J 0
(-8975 3125);
DISPLAY 0.659574 (-8975 3125);
DISPLAY INVISIBLE (-8975 3125);
FORCEPROP 1 LAST BODY_TYPE PLUMBING
J 0
(-9045 2957);
DISPLAY 0.276596 (-9045 2957);
PAINT GREEN (-9045 2957);
DISPLAY INVISIBLE (-9045 2957);
FORCEPROP 1 LAST HDL_POWER GND
J 0
(-9000 3150);
DISPLAY 0.723404 (-9000 3150);
PAINT GREEN (-9000 3150);
DISPLAY INVISIBLE (-9000 3150);
FORCEPROP 1 LAST PATH I524
J 0
(-8925 3000);
DISPLAY 0.872340 (-8925 3000);
PAINT AQUA (-8925 3000);
DISPLAY INVISIBLE (-8925 3000);
FORCEADD Q_RES..1
R 2
(-8575 2250);
FORCEPROP 1 LAST LOCATION R291
J 2
(-8550 2275);
DISPLAY 0.489362 (-8550 2275);
PAINT SKYBLUE (-8550 2275);
FORCEPROP 0 LAST $SEC 1
J 0
(-8550 2325);
DISPLAY 0.680851 (-8550 2325);
PAINT MONO (-8550 2325);
DISPLAY INVISIBLE (-8550 2325);
FORCEPROP 0 LAST CDS_SEC 1
J 0
(-8550 2325);
DISPLAY 1.021277 (-8550 2325);
DISPLAY INVISIBLE (-8550 2325);
FORCEPROP 1 LASTPIN (-8475 2250) $PN 1
J 2
(-8487 2262);
DISPLAY 0.489362 (-8487 2262);
PAINT MONO (-8487 2262);
FORCEPROP 1 LASTPIN (-8675 2250) $PN 2
J 2
(-8637 2262);
DISPLAY 0.489362 (-8637 2262);
PAINT MONO (-8637 2262);
FORCEPROP 1 LAST VALUE 1K
J 0
(-8575 2200);
DISPLAY 0.489362 (-8575 2200);
PAINT SKYBLUE (-8575 2200);
FORCEPROP 1 LAST PACK_TYPE 0402LF
J 0
(-8750 2175);
DISPLAY 0.489362 (-8750 2175);
PAINT SKYBLUE (-8750 2175);
DISPLAY INVISIBLE (-8750 2175);
FORCEPROP 1 LAST MATERIAL CHIP
J 0
(-8750 2225);
DISPLAY 0.489362 (-8750 2225);
PAINT SKYBLUE (-8750 2225);
DISPLAY INVISIBLE (-8750 2225);
FORCEPROP 1 LAST WATTAGE 1/16W
J 0
(-8500 2175);
DISPLAY 0.489362 (-8500 2175);
PAINT SKYBLUE (-8500 2175);
DISPLAY INVISIBLE (-8500 2175);
FORCEPROP 2 LAST CDS_LIB pure_quanta
J 0
(-8575 2250);
DISPLAY INVISIBLE (-8575 2250);
FORCEPROP 2 LAST BOM_COST MEM
J 0
(-8600 2400);
DISPLAY 0.744681 (-8600 2400);
PAINT WHITE (-8600 2400);
DISPLAY INVISIBLE (-8600 2400);
FORCEPROP 1 LAST TOLERANCE 1%
J 2
(-8450 2225);
DISPLAY 0.489362 (-8450 2225);
PAINT SKYBLUE (-8450 2225);
DISPLAY INVISIBLE (-8450 2225);
FORCEPROP 2 LAST ROOM 
J 0
(-8600 2350);
DISPLAY 0.744681 (-8600 2350);
PAINT RED (-8600 2350);
DISPLAY INVISIBLE (-8600 2350);
FORCEPROP 1 LAST PATH I525
J 2
(-8525 2400);
DISPLAY 0.978723 (-8525 2400);
PAINT WHITE (-8525 2400);
DISPLAY INVISIBLE (-8525 2400);
FORCEPROP 1 LAST PART_NUMBER CS21002FB06
J 0
(-8675 2300);
DISPLAY 0.489362 (-8675 2300);
PAINT SKYBLUE (-8675 2300);
DISPLAY INVISIBLE (-8675 2300);
FORCEADD Q_RES..2
R 2
(-8700 2400);
FORCEPROP 1 LAST LOCATION R88
J 2
(-8745 2525);
DISPLAY 0.489362 (-8745 2525);
PAINT SKYBLUE (-8745 2525);
FORCEPROP 0 LAST $SEC 1
J 0
(-8725 2575);
DISPLAY 0.680851 (-8725 2575);
PAINT MONO (-8725 2575);
DISPLAY INVISIBLE (-8725 2575);
FORCEPROP 0 LAST CDS_SEC 1
J 0
(-8725 2575);
DISPLAY 1.021277 (-8725 2575);
DISPLAY INVISIBLE (-8725 2575);
FORCEPROP 1 LASTPIN (-8700 2500) $PN 1
J 2
(-8705 2462);
DISPLAY 0.489362 (-8705 2462);
PAINT MONO (-8705 2462);
FORCEPROP 1 LASTPIN (-8700 2300) $PN 2
J 2
(-8705 2310);
DISPLAY 0.489362 (-8705 2310);
PAINT MONO (-8705 2310);
FORCEPROP 1 LAST TOLERANCE 1%
J 2
(-8750 2450);
DISPLAY 0.489362 (-8750 2450);
PAINT SKYBLUE (-8750 2450);
FORCEPROP 1 LAST WATTAGE 1/16W
J 2
(-8750 2425);
DISPLAY 0.489362 (-8750 2425);
PAINT SKYBLUE (-8750 2425);
FORCEPROP 1 LAST MATERIAL EMPTY
J 2
(-8750 2400);
DISPLAY 0.489362 (-8750 2400);
PAINT RED (-8750 2400);
FORCEPROP 1 LAST PACK_TYPE 0402LF
J 2
(-8750 2350);
DISPLAY 0.489362 (-8750 2350);
PAINT SKYBLUE (-8750 2350);
FORCEPROP 1 LAST VALUE 1K
J 2
(-8745 2475);
DISPLAY 0.489362 (-8745 2475);
PAINT SKYBLUE (-8745 2475);
FORCEPROP 2 LAST ROOM 
J 2
(-8750 2625);
DISPLAY 0.808511 (-8750 2625);
PAINT RED (-8750 2625);
DISPLAY INVISIBLE (-8750 2625);
FORCEPROP 2 LAST BOM_COST MEM
J 2
(-8750 2575);
DISPLAY 0.808511 (-8750 2575);
DISPLAY INVISIBLE (-8750 2575);
FORCEPROP 2 LAST CDS_LIB pure_quanta
J 2
(-8700 2400);
DISPLAY INVISIBLE (-8700 2400);
FORCEPROP 1 LAST PATH I526
J 2
(-8750 2575);
DISPLAY 0.978723 (-8750 2575);
PAINT WHITE (-8750 2575);
DISPLAY INVISIBLE (-8750 2575);
FORCEPROP 1 LAST PART_NUMBER CS21002FB06
J 2
(-8750 2375);
DISPLAY 0.489362 (-8750 2375);
PAINT SKYBLUE (-8750 2375);
DISPLAY INVISIBLE (-8750 2375);
FORCEADD VCC_CORE..1
(-8700 2575);
FORCEPROP 3 LASTPIN (-8700 2525) SIG_NAME P3V3\g
J 0
(-8690 2535);
DISPLAY 0.659574 (-8690 2535);
PAINT MONO (-8690 2535);
DISPLAY INVISIBLE (-8690 2535);
FORCEPROP 1 LAST HDL_POWER P3V3
J 1
(-8700 2625);
DISPLAY 0.489362 (-8700 2625);
PAINT GREEN (-8700 2625);
FORCEPROP 0 LAST VOLTAGE 3.3
J 0
(-8975 2725);
DISPLAY 1.021277 (-8975 2725);
PAINT SKYBLUE (-8975 2725);
DISPLAY INVISIBLE (-8975 2725);
FORCEPROP 2 LAST ROOM PVCCINFAON_CPU0_CTRL
J 0
(-8700 2675);
DISPLAY 0.808511 (-8700 2675);
PAINT RED (-8700 2675);
DISPLAY INVISIBLE (-8700 2675);
FORCEPROP 2 LAST CDS_LIB mstr_symbols
J 0
(-8700 2575);
DISPLAY INVISIBLE (-8700 2575);
FORCEPROP 1 LAST PATH I527
J 0
(-8650 2600);
DISPLAY 0.872340 (-8650 2600);
PAINT AQUA (-8650 2600);
DISPLAY INVISIBLE (-8650 2600);
FORCEADD Q_RES..2
(-8450 2400);
FORCEPROP 1 LAST LOCATION R89
J 0
(-8405 2525);
DISPLAY 0.489362 (-8405 2525);
PAINT SKYBLUE (-8405 2525);
FORCEPROP 0 LAST $SEC 1
J 0
(-8400 2575);
DISPLAY 0.680851 (-8400 2575);
PAINT MONO (-8400 2575);
DISPLAY INVISIBLE (-8400 2575);
FORCEPROP 0 LAST CDS_SEC 1
J 0
(-8400 2575);
DISPLAY 1.021277 (-8400 2575);
DISPLAY INVISIBLE (-8400 2575);
FORCEPROP 1 LASTPIN (-8450 2500) $PN 1
J 0
(-8445 2462);
DISPLAY 0.489362 (-8445 2462);
PAINT MONO (-8445 2462);
FORCEPROP 1 LASTPIN (-8450 2300) $PN 2
J 0
(-8445 2310);
DISPLAY 0.489362 (-8445 2310);
PAINT MONO (-8445 2310);
FORCEPROP 1 LAST WATTAGE 1/16W
J 0
(-8400 2425);
DISPLAY 0.489362 (-8400 2425);
PAINT SKYBLUE (-8400 2425);
FORCEPROP 1 LAST MATERIAL EMPTY
J 0
(-8400 2400);
DISPLAY 0.489362 (-8400 2400);
PAINT RED (-8400 2400);
FORCEPROP 1 LAST PACK_TYPE 0402LF
J 0
(-8400 2350);
DISPLAY 0.489362 (-8400 2350);
PAINT SKYBLUE (-8400 2350);
FORCEPROP 1 LAST TOLERANCE 1%
J 0
(-8400 2450);
DISPLAY 0.489362 (-8400 2450);
PAINT SKYBLUE (-8400 2450);
FORCEPROP 1 LAST VALUE 1K
J 0
(-8405 2475);
DISPLAY 0.489362 (-8405 2475);
PAINT SKYBLUE (-8405 2475);
FORCEPROP 2 LAST ROOM 
J 0
(-8400 2625);
DISPLAY 0.808511 (-8400 2625);
PAINT RED (-8400 2625);
DISPLAY INVISIBLE (-8400 2625);
FORCEPROP 2 LAST BOM_COST MEM
J 0
(-8400 2575);
DISPLAY 0.808511 (-8400 2575);
DISPLAY INVISIBLE (-8400 2575);
FORCEPROP 2 LAST CDS_LIB pure_quanta
J 2
(-8450 2400);
DISPLAY INVISIBLE (-8450 2400);
FORCEPROP 1 LAST PATH I528
J 0
(-8400 2575);
DISPLAY 0.978723 (-8400 2575);
PAINT WHITE (-8400 2575);
DISPLAY INVISIBLE (-8400 2575);
FORCEPROP 1 LAST PART_NUMBER CS21002FB06
J 0
(-8400 2375);
DISPLAY 0.489362 (-8400 2375);
PAINT SKYBLUE (-8400 2375);
DISPLAY INVISIBLE (-8400 2375);
FORCEADD VCC_CORE..1
(-8450 2575);
FORCEPROP 3 LASTPIN (-8450 2525) SIG_NAME P3V3\g
J 0
(-8440 2535);
DISPLAY 0.659574 (-8440 2535);
PAINT MONO (-8440 2535);
DISPLAY INVISIBLE (-8440 2535);
FORCEPROP 1 LAST HDL_POWER P3V3
J 1
(-8450 2625);
DISPLAY 0.489362 (-8450 2625);
PAINT GREEN (-8450 2625);
FORCEPROP 2 LAST ROOM PVCCINFAON_CPU0_CTRL
J 0
(-8450 2675);
DISPLAY 0.808511 (-8450 2675);
PAINT RED (-8450 2675);
DISPLAY INVISIBLE (-8450 2675);
FORCEPROP 0 LAST VOLTAGE 3.3
J 0
(-8725 2725);
DISPLAY 1.021277 (-8725 2725);
PAINT SKYBLUE (-8725 2725);
DISPLAY INVISIBLE (-8725 2725);
FORCEPROP 2 LAST CDS_LIB mstr_symbols
J 0
(-8450 2575);
DISPLAY INVISIBLE (-8450 2575);
FORCEPROP 1 LAST PATH I529
J 0
(-8400 2600);
DISPLAY 0.872340 (-8400 2600);
PAINT AQUA (-8400 2600);
DISPLAY INVISIBLE (-8400 2600);
FORCEADD Q_CAP..1
R 2
(-2375 6050);
FORCEPROP 1 LAST LOCATION C142
J 2
(-2425 6150);
DISPLAY 0.489362 (-2425 6150);
PAINT SKYBLUE (-2425 6150);
FORCEPROP 0 LAST $SEC 1
J 0
(-2425 6200);
DISPLAY 0.680851 (-2425 6200);
PAINT MONO (-2425 6200);
DISPLAY INVISIBLE (-2425 6200);
FORCEPROP 0 LAST CDS_SEC 1
J 0
(-2425 6200);
DISPLAY 0.680851 (-2425 6200);
DISPLAY INVISIBLE (-2425 6200);
FORCEPROP 1 LASTPIN (-2375 6150) $PN 1
J 2
(-2385 6130);
DISPLAY 0.489362 (-2385 6130);
PAINT MONO (-2385 6130);
FORCEPROP 1 LASTPIN (-2375 5950) $PN 2
J 2
(-2385 5930);
DISPLAY 0.489362 (-2385 5930);
PAINT MONO (-2385 5930);
FORCEPROP 1 LAST MATERIAL X6S
J 2
(-2425 5950);
DISPLAY 0.489362 (-2425 5950);
PAINT SKYBLUE (-2425 5950);
FORCEPROP 1 LAST VOLTAGE 25V
J 2
(-2425 6050);
DISPLAY 0.489362 (-2425 6050);
PAINT SKYBLUE (-2425 6050);
FORCEPROP 1 LAST PACK_TYPE C0805
J 2
(-2425 5850);
DISPLAY 0.489362 (-2425 5850);
PAINT SKYBLUE (-2425 5850);
FORCEPROP 1 LAST VALUE 10UF
J 2
(-2425 6100);
DISPLAY 0.489362 (-2425 6100);
PAINT SKYBLUE (-2425 6100);
FORCEPROP 1 LAST TOLERANCE 10%
J 2
(-2425 6000);
DISPLAY 0.489362 (-2425 6000);
PAINT SKYBLUE (-2425 6000);
FORCEPROP 2 LAST ROOM 
J 2
(-2430 6195);
DISPLAY 0.595745 (-2430 6195);
PAINT RED (-2430 6195);
DISPLAY INVISIBLE (-2430 6195);
FORCEPROP 2 LAST CDS_LIB pure_quanta
J 0
(-2375 6050);
DISPLAY INVISIBLE (-2375 6050);
FORCEPROP 0 LAST BOM_COST MEM
J 2
(-2430 6195);
DISPLAY 0.595745 (-2430 6195);
PAINT MONO (-2430 6195);
DISPLAY INVISIBLE (-2430 6195);
FORCEPROP 1 LAST PATH I534
J 2
(-2425 6200);
DISPLAY 0.978723 (-2425 6200);
PAINT WHITE (-2425 6200);
DISPLAY INVISIBLE (-2425 6200);
FORCEPROP 1 LAST PART_NUMBER CH6104KEA00
J 2
(-2425 5900);
DISPLAY 0.489362 (-2425 5900);
PAINT SKYBLUE (-2425 5900);
DISPLAY INVISIBLE (-2425 5900);
FORCEADD UNIVERSAL_POWER..1
(-2950 6375);
FORCEPROP 3 LASTPIN (-2950 6325) SIG_NAME P12V_MEM_CPU0\g
J 0
(-2940 6335);
DISPLAY 0.659574 (-2940 6335);
PAINT MONO (-2940 6335);
DISPLAY INVISIBLE (-2940 6335);
FORCEPROP 1 LAST HDL_POWER P12V_MEM_CPU0
J 1
(-2975 6425);
DISPLAY 0.489362 (-2975 6425);
PAINT GREEN (-2975 6425);
FORCEPROP 2 LAST CDS_LIB pure_quanta_power
J 0
(-2950 6375);
DISPLAY INVISIBLE (-2950 6375);
FORCEPROP 2 LAST BOM_COST VR_SYSTEM
J 0
(-2950 6475);
DISPLAY 0.617021 (-2950 6475);
PAINT PURPLE (-2950 6475);
DISPLAY INVISIBLE (-2950 6475);
FORCEPROP 1 LAST PATH I535
J 0
(-2900 6400);
DISPLAY 0.872340 (-2900 6400);
PAINT AQUA (-2900 6400);
DISPLAY INVISIBLE (-2900 6400);
FORCEADD SCONN288_DDR506112002KQ..1
(-6900 3675);
FORCEPROP 1 LAST LOCATION J1
J 0
(-7350 5675);
DISPLAY 0.574468 (-7350 5675);
PAINT SKYBLUE (-7350 5675);
FORCEPROP 0 LAST $SEC 1
J 0
(-7350 5825);
DISPLAY 0.680851 (-7350 5825);
PAINT MONO (-7350 5825);
DISPLAY INVISIBLE (-7350 5825);
FORCEPROP 0 LAST CDS_SEC 1
J 0
(-7350 5825);
DISPLAY 0.680851 (-7350 5825);
DISPLAY INVISIBLE (-7350 5825);
FORCEPROP 0 LASTPIN (-7500 3075) $PN 62
J 2
(-7510 3085);
DISPLAY 0.680851 (-7510 3085);
PAINT MONO (-7510 3085);
FORCEPROP 0 LASTPIN (-7500 5125) $PN 66
J 2
(-7510 5135);
DISPLAY 0.680851 (-7510 5135);
PAINT MONO (-7510 5135);
FORCEPROP 0 LASTPIN (-7500 4725) $PN 76
J 2
(-7510 4735);
DISPLAY 0.680851 (-7510 4735);
PAINT MONO (-7510 4735);
FORCEPROP 0 LASTPIN (-7500 5175) $PN 211
J 2
(-7510 5185);
DISPLAY 0.680851 (-7510 5185);
PAINT MONO (-7510 5185);
FORCEPROP 0 LASTPIN (-7500 4775) $PN 221
J 2
(-7510 4785);
DISPLAY 0.680851 (-7510 4785);
PAINT MONO (-7510 4785);
FORCEPROP 0 LASTPIN (-7500 5225) $PN 68
J 2
(-7510 5235);
DISPLAY 0.680851 (-7510 5235);
PAINT MONO (-7510 5235);
FORCEPROP 0 LASTPIN (-7500 4825) $PN 78
J 2
(-7510 4835);
DISPLAY 0.680851 (-7510 4835);
PAINT MONO (-7510 4835);
FORCEPROP 0 LASTPIN (-7500 5275) $PN 213
J 2
(-7510 5285);
DISPLAY 0.680851 (-7510 5285);
PAINT MONO (-7510 5285);
FORCEPROP 0 LASTPIN (-7500 4875) $PN 223
J 2
(-7510 4885);
DISPLAY 0.680851 (-7510 4885);
PAINT MONO (-7510 4885);
FORCEPROP 0 LASTPIN (-7500 5325) $PN 70
J 2
(-7510 5335);
DISPLAY 0.680851 (-7510 5335);
PAINT MONO (-7510 5335);
FORCEPROP 0 LASTPIN (-7500 4925) $PN 80
J 2
(-7510 4935);
DISPLAY 0.680851 (-7510 4935);
PAINT MONO (-7510 4935);
FORCEPROP 0 LASTPIN (-7500 5375) $PN 215
J 2
(-7510 5385);
DISPLAY 0.680851 (-7510 5385);
PAINT MONO (-7510 5385);
FORCEPROP 0 LASTPIN (-7500 4975) $PN 225
J 2
(-7510 4985);
DISPLAY 0.680851 (-7510 4985);
PAINT MONO (-7510 4985);
FORCEPROP 0 LASTPIN (-7500 5425) $PN 72
J 2
(-7510 5435);
DISPLAY 0.680851 (-7510 5435);
PAINT MONO (-7510 5435);
FORCEPROP 0 LASTPIN (-7500 5025) $PN 82
J 2
(-7510 5035);
DISPLAY 0.680851 (-7510 5035);
PAINT MONO (-7510 5035);
FORCEPROP 0 LASTPIN (-7500 3675) $PN 51
J 2
(-7510 3685);
DISPLAY 0.680851 (-7510 3685);
PAINT MONO (-7510 3685);
FORCEPROP 0 LASTPIN (-7500 3225) $PN 96
J 2
(-7510 3235);
DISPLAY 0.680851 (-7510 3235);
PAINT MONO (-7510 3235);
FORCEPROP 0 LASTPIN (-7500 3725) $PN 53
J 2
(-7510 3735);
DISPLAY 0.680851 (-7510 3735);
PAINT MONO (-7510 3735);
FORCEPROP 0 LASTPIN (-7500 3275) $PN 98
J 2
(-7510 3285);
DISPLAY 0.680851 (-7510 3285);
PAINT MONO (-7510 3285);
FORCEPROP 0 LASTPIN (-7500 3775) $PN 196
J 2
(-7510 3785);
DISPLAY 0.680851 (-7510 3785);
PAINT MONO (-7510 3785);
FORCEPROP 0 LASTPIN (-7500 3325) $PN 241
J 2
(-7510 3335);
DISPLAY 0.680851 (-7510 3335);
PAINT MONO (-7510 3335);
FORCEPROP 0 LASTPIN (-7500 3825) $PN 198
J 2
(-7510 3835);
DISPLAY 0.680851 (-7510 3835);
PAINT MONO (-7510 3835);
FORCEPROP 0 LASTPIN (-7500 3375) $PN 243
J 2
(-7510 3385);
DISPLAY 0.680851 (-7510 3385);
PAINT MONO (-7510 3385);
FORCEPROP 0 LASTPIN (-7500 3875) $PN 58
J 2
(-7510 3885);
DISPLAY 0.680851 (-7510 3885);
PAINT MONO (-7510 3885);
FORCEPROP 0 LASTPIN (-7500 3425) $PN 89
J 2
(-7510 3435);
DISPLAY 0.680851 (-7510 3435);
PAINT MONO (-7510 3435);
FORCEPROP 0 LASTPIN (-7500 3925) $PN 60
J 2
(-7510 3935);
DISPLAY 0.680851 (-7510 3935);
PAINT MONO (-7510 3935);
FORCEPROP 0 LASTPIN (-7500 3475) $PN 91
J 2
(-7510 3485);
DISPLAY 0.680851 (-7510 3485);
PAINT MONO (-7510 3485);
FORCEPROP 0 LASTPIN (-7500 3975) $PN 203
J 2
(-7510 3985);
DISPLAY 0.680851 (-7510 3985);
PAINT MONO (-7510 3985);
FORCEPROP 0 LASTPIN (-7500 3525) $PN 234
J 2
(-7510 3535);
DISPLAY 0.680851 (-7510 3535);
PAINT MONO (-7510 3535);
FORCEPROP 0 LASTPIN (-7500 4025) $PN 205
J 2
(-7510 4035);
DISPLAY 0.680851 (-7510 4035);
PAINT MONO (-7510 4035);
FORCEPROP 0 LASTPIN (-7500 3575) $PN 236
J 2
(-7510 3585);
DISPLAY 0.680851 (-7510 3585);
PAINT MONO (-7510 3585);
FORCEPROP 0 LASTPIN (-7500 4125) $PN 218
J 2
(-7510 4135);
DISPLAY 0.680851 (-7510 4135);
PAINT MONO (-7510 4135);
FORCEPROP 0 LASTPIN (-7500 4175) $PN 217
J 2
(-7510 4185);
DISPLAY 0.680851 (-7510 4185);
PAINT MONO (-7510 4185);
FORCEPROP 0 LASTPIN (-7500 4425) $PN 64
J 2
(-7510 4435);
DISPLAY 0.680851 (-7510 4435);
PAINT MONO (-7510 4435);
FORCEPROP 0 LASTPIN (-7500 4275) $PN 84
J 2
(-7510 4285);
DISPLAY 0.680851 (-7510 4285);
PAINT MONO (-7510 4285);
FORCEPROP 0 LASTPIN (-7500 4475) $PN 209
J 2
(-7510 4485);
DISPLAY 0.680851 (-7510 4485);
PAINT MONO (-7510 4485);
FORCEPROP 0 LASTPIN (-7500 4325) $PN 229
J 2
(-7510 4335);
DISPLAY 0.680851 (-7510 4335);
PAINT MONO (-7510 4335);
FORCEPROP 0 LASTPIN (-6300 3875) $PN 7
J 0
(-6290 3885);
DISPLAY 0.680851 (-6290 3885);
PAINT MONO (-6290 3885);
FORCEPROP 0 LASTPIN (-6300 2225) $PN 100
J 0
(-6290 2235);
DISPLAY 0.680851 (-6290 2235);
PAINT MONO (-6290 2235);
FORCEPROP 0 LASTPIN (-6300 3925) $PN 9
J 0
(-6290 3935);
DISPLAY 0.680851 (-6290 3935);
PAINT MONO (-6290 3935);
FORCEPROP 0 LASTPIN (-6300 2275) $PN 102
J 0
(-6290 2285);
DISPLAY 0.680851 (-6290 2285);
PAINT MONO (-6290 2285);
FORCEPROP 0 LASTPIN (-6300 3975) $PN 152
J 0
(-6290 3985);
DISPLAY 0.680851 (-6290 3985);
PAINT MONO (-6290 3985);
FORCEPROP 0 LASTPIN (-6300 2325) $PN 245
J 0
(-6290 2335);
DISPLAY 0.680851 (-6290 2335);
PAINT MONO (-6290 2335);
FORCEPROP 0 LASTPIN (-6300 4025) $PN 154
J 0
(-6290 4035);
DISPLAY 0.680851 (-6290 4035);
PAINT MONO (-6290 4035);
FORCEPROP 0 LASTPIN (-6300 2375) $PN 247
J 0
(-6290 2385);
DISPLAY 0.680851 (-6290 2385);
PAINT MONO (-6290 2385);
FORCEPROP 0 LASTPIN (-6300 4075) $PN 14
J 0
(-6290 4085);
DISPLAY 0.680851 (-6290 4085);
PAINT MONO (-6290 4085);
FORCEPROP 0 LASTPIN (-6300 2425) $PN 107
J 0
(-6290 2435);
DISPLAY 0.680851 (-6290 2435);
PAINT MONO (-6290 2435);
FORCEPROP 0 LASTPIN (-6300 4125) $PN 16
J 0
(-6290 4135);
DISPLAY 0.680851 (-6290 4135);
PAINT MONO (-6290 4135);
FORCEPROP 0 LASTPIN (-6300 2475) $PN 109
J 0
(-6290 2485);
DISPLAY 0.680851 (-6290 2485);
PAINT MONO (-6290 2485);
FORCEPROP 0 LASTPIN (-6300 4175) $PN 159
J 0
(-6290 4185);
DISPLAY 0.680851 (-6290 4185);
PAINT MONO (-6290 4185);
FORCEPROP 0 LASTPIN (-6300 2525) $PN 252
J 0
(-6290 2535);
DISPLAY 0.680851 (-6290 2535);
PAINT MONO (-6290 2535);
FORCEPROP 0 LASTPIN (-6300 4225) $PN 161
J 0
(-6290 4235);
DISPLAY 0.680851 (-6290 4235);
PAINT MONO (-6290 4235);
FORCEPROP 0 LASTPIN (-6300 2575) $PN 254
J 0
(-6290 2585);
DISPLAY 0.680851 (-6290 2585);
PAINT MONO (-6290 2585);
FORCEPROP 0 LASTPIN (-6300 4275) $PN 18
J 0
(-6290 4285);
DISPLAY 0.680851 (-6290 4285);
PAINT MONO (-6290 4285);
FORCEPROP 0 LASTPIN (-6300 2625) $PN 111
J 0
(-6290 2635);
DISPLAY 0.680851 (-6290 2635);
PAINT MONO (-6290 2635);
FORCEPROP 0 LASTPIN (-6300 4325) $PN 20
J 0
(-6290 4335);
DISPLAY 0.680851 (-6290 4335);
PAINT MONO (-6290 4335);
FORCEPROP 0 LASTPIN (-6300 2675) $PN 113
J 0
(-6290 2685);
DISPLAY 0.680851 (-6290 2685);
PAINT MONO (-6290 2685);
FORCEPROP 0 LASTPIN (-6300 4375) $PN 163
J 0
(-6290 4385);
DISPLAY 0.680851 (-6290 4385);
PAINT MONO (-6290 4385);
FORCEPROP 0 LASTPIN (-6300 2725) $PN 256
J 0
(-6290 2735);
DISPLAY 0.680851 (-6290 2735);
PAINT MONO (-6290 2735);
FORCEPROP 0 LASTPIN (-6300 4425) $PN 165
J 0
(-6290 4435);
DISPLAY 0.680851 (-6290 4435);
PAINT MONO (-6290 4435);
FORCEPROP 0 LASTPIN (-6300 2775) $PN 258
J 0
(-6290 2785);
DISPLAY 0.680851 (-6290 2785);
PAINT MONO (-6290 2785);
FORCEPROP 0 LASTPIN (-6300 4475) $PN 25
J 0
(-6290 4485);
DISPLAY 0.680851 (-6290 4485);
PAINT MONO (-6290 4485);
FORCEPROP 0 LASTPIN (-6300 2825) $PN 118
J 0
(-6290 2835);
DISPLAY 0.680851 (-6290 2835);
PAINT MONO (-6290 2835);
FORCEPROP 0 LASTPIN (-6300 4525) $PN 27
J 0
(-6290 4535);
DISPLAY 0.680851 (-6290 4535);
PAINT MONO (-6290 4535);
FORCEPROP 0 LASTPIN (-6300 2875) $PN 120
J 0
(-6290 2885);
DISPLAY 0.680851 (-6290 2885);
PAINT MONO (-6290 2885);
FORCEPROP 0 LASTPIN (-6300 4575) $PN 170
J 0
(-6290 4585);
DISPLAY 0.680851 (-6290 4585);
PAINT MONO (-6290 4585);
FORCEPROP 0 LASTPIN (-6300 2925) $PN 263
J 0
(-6290 2935);
DISPLAY 0.680851 (-6290 2935);
PAINT MONO (-6290 2935);
FORCEPROP 0 LASTPIN (-6300 4625) $PN 172
J 0
(-6290 4635);
DISPLAY 0.680851 (-6290 4635);
PAINT MONO (-6290 4635);
FORCEPROP 0 LASTPIN (-6300 2975) $PN 265
J 0
(-6290 2985);
DISPLAY 0.680851 (-6290 2985);
PAINT MONO (-6290 2985);
FORCEPROP 0 LASTPIN (-6300 4675) $PN 29
J 0
(-6290 4685);
DISPLAY 0.680851 (-6290 4685);
PAINT MONO (-6290 4685);
FORCEPROP 0 LASTPIN (-6300 3025) $PN 122
J 0
(-6290 3035);
DISPLAY 0.680851 (-6290 3035);
PAINT MONO (-6290 3035);
FORCEPROP 0 LASTPIN (-6300 4725) $PN 31
J 0
(-6290 4735);
DISPLAY 0.680851 (-6290 4735);
PAINT MONO (-6290 4735);
FORCEPROP 0 LASTPIN (-6300 3075) $PN 124
J 0
(-6290 3085);
DISPLAY 0.680851 (-6290 3085);
PAINT MONO (-6290 3085);
FORCEPROP 0 LASTPIN (-6300 4775) $PN 174
J 0
(-6290 4785);
DISPLAY 0.680851 (-6290 4785);
PAINT MONO (-6290 4785);
FORCEPROP 0 LASTPIN (-6300 3125) $PN 267
J 0
(-6290 3135);
DISPLAY 0.680851 (-6290 3135);
PAINT MONO (-6290 3135);
FORCEPROP 0 LASTPIN (-6300 4825) $PN 176
J 0
(-6290 4835);
DISPLAY 0.680851 (-6290 4835);
PAINT MONO (-6290 4835);
FORCEPROP 0 LASTPIN (-6300 3175) $PN 269
J 0
(-6290 3185);
DISPLAY 0.680851 (-6290 3185);
PAINT MONO (-6290 3185);
FORCEPROP 0 LASTPIN (-6300 4875) $PN 36
J 0
(-6290 4885);
DISPLAY 0.680851 (-6290 4885);
PAINT MONO (-6290 4885);
FORCEPROP 0 LASTPIN (-6300 3225) $PN 129
J 0
(-6290 3235);
DISPLAY 0.680851 (-6290 3235);
PAINT MONO (-6290 3235);
FORCEPROP 0 LASTPIN (-6300 4925) $PN 38
J 0
(-6290 4935);
DISPLAY 0.680851 (-6290 4935);
PAINT MONO (-6290 4935);
FORCEPROP 0 LASTPIN (-6300 3275) $PN 131
J 0
(-6290 3285);
DISPLAY 0.680851 (-6290 3285);
PAINT MONO (-6290 3285);
FORCEPROP 0 LASTPIN (-6300 4975) $PN 181
J 0
(-6290 4985);
DISPLAY 0.680851 (-6290 4985);
PAINT MONO (-6290 4985);
FORCEPROP 0 LASTPIN (-6300 3325) $PN 274
J 0
(-6290 3335);
DISPLAY 0.680851 (-6290 3335);
PAINT MONO (-6290 3335);
FORCEPROP 0 LASTPIN (-6300 5025) $PN 183
J 0
(-6290 5035);
DISPLAY 0.680851 (-6290 5035);
PAINT MONO (-6290 5035);
FORCEPROP 0 LASTPIN (-6300 3375) $PN 276
J 0
(-6290 3385);
DISPLAY 0.680851 (-6290 3385);
PAINT MONO (-6290 3385);
FORCEPROP 0 LASTPIN (-6300 5075) $PN 40
J 0
(-6290 5085);
DISPLAY 0.680851 (-6290 5085);
PAINT MONO (-6290 5085);
FORCEPROP 0 LASTPIN (-6300 3425) $PN 133
J 0
(-6290 3435);
DISPLAY 0.680851 (-6290 3435);
PAINT MONO (-6290 3435);
FORCEPROP 0 LASTPIN (-6300 5125) $PN 42
J 0
(-6290 5135);
DISPLAY 0.680851 (-6290 5135);
PAINT MONO (-6290 5135);
FORCEPROP 0 LASTPIN (-6300 3475) $PN 135
J 0
(-6290 3485);
DISPLAY 0.680851 (-6290 3485);
PAINT MONO (-6290 3485);
FORCEPROP 0 LASTPIN (-6300 5175) $PN 185
J 0
(-6290 5185);
DISPLAY 0.680851 (-6290 5185);
PAINT MONO (-6290 5185);
FORCEPROP 0 LASTPIN (-6300 3525) $PN 278
J 0
(-6290 3535);
DISPLAY 0.680851 (-6290 3535);
PAINT MONO (-6290 3535);
FORCEPROP 0 LASTPIN (-6300 5225) $PN 187
J 0
(-6290 5235);
DISPLAY 0.680851 (-6290 5235);
PAINT MONO (-6290 5235);
FORCEPROP 0 LASTPIN (-6300 3575) $PN 280
J 0
(-6290 3585);
DISPLAY 0.680851 (-6290 3585);
PAINT MONO (-6290 3585);
FORCEPROP 0 LASTPIN (-6300 5275) $PN 47
J 0
(-6290 5285);
DISPLAY 0.680851 (-6290 5285);
PAINT MONO (-6290 5285);
FORCEPROP 0 LASTPIN (-6300 3625) $PN 140
J 0
(-6290 3635);
DISPLAY 0.680851 (-6290 3635);
PAINT MONO (-6290 3635);
FORCEPROP 0 LASTPIN (-6300 5325) $PN 49
J 0
(-6290 5335);
DISPLAY 0.680851 (-6290 5335);
PAINT MONO (-6290 5335);
FORCEPROP 0 LASTPIN (-6300 3675) $PN 142
J 0
(-6290 3685);
DISPLAY 0.680851 (-6290 3685);
PAINT MONO (-6290 3685);
FORCEPROP 0 LASTPIN (-6300 5375) $PN 192
J 0
(-6290 5385);
DISPLAY 0.680851 (-6290 5385);
PAINT MONO (-6290 5385);
FORCEPROP 0 LASTPIN (-6300 3725) $PN 285
J 0
(-6290 3735);
DISPLAY 0.680851 (-6290 3735);
PAINT MONO (-6290 3735);
FORCEPROP 0 LASTPIN (-6300 5425) $PN 194
J 0
(-6290 5435);
DISPLAY 0.680851 (-6290 5435);
PAINT MONO (-6290 5435);
FORCEPROP 0 LASTPIN (-6300 3775) $PN 287
J 0
(-6290 3785);
DISPLAY 0.680851 (-6290 3785);
PAINT MONO (-6290 3785);
FORCEPROP 0 LASTPIN (-7500 2925) $PN 148
J 2
(-7510 2935);
DISPLAY 0.680851 (-7510 2935);
PAINT MONO (-7510 2935);
FORCEPROP 0 LASTPIN (-7500 2825) $PN 4
J 2
(-7510 2835);
DISPLAY 0.680851 (-7510 2835);
PAINT MONO (-7510 2835);
FORCEPROP 0 LASTPIN (-7500 2875) $PN 5
J 2
(-7510 2885);
DISPLAY 0.680851 (-7510 2885);
PAINT MONO (-7510 2885);
FORCEPROP 0 LASTPIN (-7500 2025) $PN 86
J 2
(-7510 2035);
DISPLAY 0.680851 (-7510 2035);
PAINT MONO (-7510 2035);
FORCEPROP 0 LASTPIN (-7500 1975) $PN 87
J 2
(-7510 1985);
DISPLAY 0.680851 (-7510 1985);
PAINT MONO (-7510 1985);
FORCEPROP 0 LASTPIN (-7500 4625) $PN 74
J 2
(-7510 4635);
DISPLAY 0.680851 (-7510 4635);
PAINT MONO (-7510 4635);
FORCEPROP 0 LASTPIN (-7500 4575) $PN 227
J 2
(-7510 4585);
DISPLAY 0.680851 (-7510 4585);
PAINT MONO (-7510 4585);
FORCEPROP 0 LASTPIN (-7500 2575) $PN 147
J 2
(-7510 2585);
DISPLAY 0.680851 (-7510 2585);
PAINT MONO (-7510 2585);
FORCEPROP 0 LASTPIN (-7500 3125) $PN 207
J 2
(-7510 3135);
DISPLAY 0.680851 (-7510 3135);
PAINT MONO (-7510 3135);
FORCEPROP 0 LASTPIN (-7500 2175) $PN 2
J 2
(-7510 2185);
DISPLAY 0.680851 (-7510 2185);
PAINT MONO (-7510 2185);
FORCEPROP 0 LASTPIN (-7500 2225) $PN 144
J 2
(-7510 2235);
DISPLAY 0.680851 (-7510 2235);
PAINT MONO (-7510 2235);
FORCEPROP 0 LASTPIN (-7500 2275) $PN 149
J 2
(-7510 2285);
DISPLAY 0.680851 (-7510 2285);
PAINT MONO (-7510 2285);
FORCEPROP 0 LASTPIN (-7500 2325) $PN 150
J 2
(-7510 2335);
DISPLAY 0.680851 (-7510 2335);
PAINT MONO (-7510 2335);
FORCEPROP 0 LASTPIN (-7500 2375) $PN 220
J 2
(-7510 2385);
DISPLAY 0.680851 (-7510 2385);
PAINT MONO (-7510 2385);
FORCEPROP 0 LASTPIN (-7500 2425) $PN 231
J 2
(-7510 2435);
DISPLAY 0.680851 (-7510 2435);
PAINT MONO (-7510 2435);
FORCEPROP 0 LASTPIN (-7500 2475) $PN 232
J 2
(-7510 2485);
DISPLAY 0.680851 (-7510 2485);
PAINT MONO (-7510 2485);
FORCEPROP 0 LASTPIN (-7500 2975) $PN 3
J 2
(-7510 2985);
DISPLAY 0.680851 (-7510 2985);
PAINT MONO (-7510 2985);
FORCEPROP 0 LAST VALUE SCONN288_DDR506112002KQ
J 0
(-7350 5725);
DISPLAY 0.446809 (-7350 5725);
PAINT SKYBLUE (-7350 5725);
FORCEPROP 2 LAST PART_TYPE SMLF
J 0
(-7350 5775);
DISPLAY 0.680851 (-7350 5775);
FORCEPROP 1 LAST MATERIAL IO
J 0
(-7350 5600);
DISPLAY 0.468085 (-7350 5600);
PAINT SKYBLUE (-7350 5600);
FORCEPROP 2 LAST CDS_LIB pure_quanta
J 0
(-6900 3675);
DISPLAY INVISIBLE (-6900 3675);
FORCEPROP 1 LAST CDS_LMAN_SYM_OUTLINE -450,1900,450,-1850
J 0
(-6900 3675);
DISPLAY 0.468085 (-6900 3675);
PAINT GREEN (-6900 3675);
DISPLAY INVISIBLE (-6900 3675);
FORCEPROP 1 LAST NEEDS_NO_SIZE TRUE
J 0
(-6900 3675);
DISPLAY 0.723404 (-6900 3675);
PAINT GREEN (-6900 3675);
DISPLAY INVISIBLE (-6900 3675);
FORCEPROP 1 LAST PATH I536
J 0
(-6900 3675);
DISPLAY 0.723404 (-6900 3675);
PAINT GREEN (-6900 3675);
DISPLAY INVISIBLE (-6900 3675);
FORCEPROP 1 LAST PART_NUMBER DFHST8FS479
J 0
(-7350 5650);
DISPLAY 0.468085 (-7350 5650);
PAINT SKYBLUE (-7350 5650);
DISPLAY INVISIBLE (-7350 5650);
FORCEADD SCONN288_DDR506112002KQ..2
(-4600 4375);
FORCEPROP 1 LAST LOCATION J1
J 0
(-5200 5675);
DISPLAY 0.468085 (-5200 5675);
PAINT SKYBLUE (-5200 5675);
FORCEPROP 0 LAST $SEC 2
J 0
(-5200 5850);
DISPLAY 0.680851 (-5200 5850);
PAINT MONO (-5200 5850);
DISPLAY INVISIBLE (-5200 5850);
FORCEPROP 0 LAST CDS_SEC 2
J 0
(-5200 5850);
DISPLAY 0.680851 (-5200 5850);
DISPLAY INVISIBLE (-5200 5850);
FORCEPROP 0 LASTPIN (-3850 4425) $PN 12
J 0
(-3840 4435);
DISPLAY 0.680851 (-3840 4435);
PAINT MONO (-3840 4435);
FORCEPROP 0 LASTPIN (-3850 4475) $PN 11
J 0
(-3840 4485);
DISPLAY 0.680851 (-3840 4485);
PAINT MONO (-3840 4485);
FORCEPROP 0 LASTPIN (-3850 3375) $PN 105
J 0
(-3840 3385);
DISPLAY 0.680851 (-3840 3385);
PAINT MONO (-3840 3385);
FORCEPROP 0 LASTPIN (-3850 3425) $PN 104
J 0
(-3840 3435);
DISPLAY 0.680851 (-3840 3435);
PAINT MONO (-3840 3435);
FORCEPROP 0 LASTPIN (-3850 4525) $PN 23
J 0
(-3840 4535);
DISPLAY 0.680851 (-3840 4535);
PAINT MONO (-3840 4535);
FORCEPROP 0 LASTPIN (-3850 4575) $PN 22
J 0
(-3840 4585);
DISPLAY 0.680851 (-3840 4585);
PAINT MONO (-3840 4585);
FORCEPROP 0 LASTPIN (-3850 3475) $PN 116
J 0
(-3840 3485);
DISPLAY 0.680851 (-3840 3485);
PAINT MONO (-3840 3485);
FORCEPROP 0 LASTPIN (-3850 3525) $PN 115
J 0
(-3840 3535);
DISPLAY 0.680851 (-3840 3535);
PAINT MONO (-3840 3535);
FORCEPROP 0 LASTPIN (-3850 4625) $PN 34
J 0
(-3840 4635);
DISPLAY 0.680851 (-3840 4635);
PAINT MONO (-3840 4635);
FORCEPROP 0 LASTPIN (-3850 4675) $PN 33
J 0
(-3840 4685);
DISPLAY 0.680851 (-3840 4685);
PAINT MONO (-3840 4685);
FORCEPROP 0 LASTPIN (-3850 3575) $PN 127
J 0
(-3840 3585);
DISPLAY 0.680851 (-3840 3585);
PAINT MONO (-3840 3585);
FORCEPROP 0 LASTPIN (-3850 3625) $PN 126
J 0
(-3840 3635);
DISPLAY 0.680851 (-3840 3635);
PAINT MONO (-3840 3635);
FORCEPROP 0 LASTPIN (-3850 4725) $PN 45
J 0
(-3840 4735);
DISPLAY 0.680851 (-3840 4735);
PAINT MONO (-3840 4735);
FORCEPROP 0 LASTPIN (-3850 4775) $PN 44
J 0
(-3840 4785);
DISPLAY 0.680851 (-3840 4785);
PAINT MONO (-3840 4785);
FORCEPROP 0 LASTPIN (-3850 3675) $PN 138
J 0
(-3840 3685);
DISPLAY 0.680851 (-3840 3685);
PAINT MONO (-3840 3685);
FORCEPROP 0 LASTPIN (-3850 3725) $PN 137
J 0
(-3840 3735);
DISPLAY 0.680851 (-3840 3735);
PAINT MONO (-3840 3735);
FORCEPROP 0 LASTPIN (-3850 4825) $PN 56
J 0
(-3840 4835);
DISPLAY 0.680851 (-3840 4835);
PAINT MONO (-3840 4835);
FORCEPROP 0 LASTPIN (-3850 4875) $PN 55
J 0
(-3840 4885);
DISPLAY 0.680851 (-3840 4885);
PAINT MONO (-3840 4885);
FORCEPROP 0 LASTPIN (-3850 3775) $PN 238
J 0
(-3840 3785);
DISPLAY 0.680851 (-3840 3785);
PAINT MONO (-3840 3785);
FORCEPROP 0 LASTPIN (-3850 3825) $PN 239
J 0
(-3840 3835);
DISPLAY 0.680851 (-3840 3835);
PAINT MONO (-3840 3835);
FORCEPROP 0 LASTPIN (-3850 4925) $PN 156
J 0
(-3840 4935);
DISPLAY 0.680851 (-3840 4935);
PAINT MONO (-3840 4935);
FORCEPROP 0 LASTPIN (-3850 4975) $PN 157
J 0
(-3840 4985);
DISPLAY 0.680851 (-3840 4985);
PAINT MONO (-3840 4985);
FORCEPROP 0 LASTPIN (-3850 3875) $PN 249
J 0
(-3840 3885);
DISPLAY 0.680851 (-3840 3885);
PAINT MONO (-3840 3885);
FORCEPROP 0 LASTPIN (-3850 3925) $PN 250
J 0
(-3840 3935);
DISPLAY 0.680851 (-3840 3935);
PAINT MONO (-3840 3935);
FORCEPROP 0 LASTPIN (-3850 5025) $PN 167
J 0
(-3840 5035);
DISPLAY 0.680851 (-3840 5035);
PAINT MONO (-3840 5035);
FORCEPROP 0 LASTPIN (-3850 5075) $PN 168
J 0
(-3840 5085);
DISPLAY 0.680851 (-3840 5085);
PAINT MONO (-3840 5085);
FORCEPROP 0 LASTPIN (-3850 3975) $PN 260
J 0
(-3840 3985);
DISPLAY 0.680851 (-3840 3985);
PAINT MONO (-3840 3985);
FORCEPROP 0 LASTPIN (-3850 4025) $PN 261
J 0
(-3840 4035);
DISPLAY 0.680851 (-3840 4035);
PAINT MONO (-3840 4035);
FORCEPROP 0 LASTPIN (-3850 5125) $PN 178
J 0
(-3840 5135);
DISPLAY 0.680851 (-3840 5135);
PAINT MONO (-3840 5135);
FORCEPROP 0 LASTPIN (-3850 5175) $PN 179
J 0
(-3840 5185);
DISPLAY 0.680851 (-3840 5185);
PAINT MONO (-3840 5185);
FORCEPROP 0 LASTPIN (-3850 4075) $PN 271
J 0
(-3840 4085);
DISPLAY 0.680851 (-3840 4085);
PAINT MONO (-3840 4085);
FORCEPROP 0 LASTPIN (-3850 4125) $PN 272
J 0
(-3840 4135);
DISPLAY 0.680851 (-3840 4135);
PAINT MONO (-3840 4135);
FORCEPROP 0 LASTPIN (-3850 5225) $PN 189
J 0
(-3840 5235);
DISPLAY 0.680851 (-3840 5235);
PAINT MONO (-3840 5235);
FORCEPROP 0 LASTPIN (-3850 5275) $PN 190
J 0
(-3840 5285);
DISPLAY 0.680851 (-3840 5285);
PAINT MONO (-3840 5285);
FORCEPROP 0 LASTPIN (-3850 4175) $PN 282
J 0
(-3840 4185);
DISPLAY 0.680851 (-3840 4185);
PAINT MONO (-3840 4185);
FORCEPROP 0 LASTPIN (-3850 4225) $PN 283
J 0
(-3840 4235);
DISPLAY 0.680851 (-3840 4235);
PAINT MONO (-3840 4235);
FORCEPROP 0 LASTPIN (-3850 5325) $PN 200
J 0
(-3840 5335);
DISPLAY 0.680851 (-3840 5335);
PAINT MONO (-3840 5335);
FORCEPROP 0 LASTPIN (-3850 5375) $PN 201
J 0
(-3840 5385);
DISPLAY 0.680851 (-3840 5385);
PAINT MONO (-3840 5385);
FORCEPROP 0 LASTPIN (-3850 4275) $PN 94
J 0
(-3840 4285);
DISPLAY 0.680851 (-3840 4285);
PAINT MONO (-3840 4285);
FORCEPROP 0 LASTPIN (-3850 4325) $PN 93
J 0
(-3840 4335);
DISPLAY 0.680851 (-3840 4335);
PAINT MONO (-3840 4335);
FORCEPROP 2 LAST PART_TYPE SMLF
J 0
(-5200 5800);
DISPLAY 0.680851 (-5200 5800);
FORCEPROP 2 LAST VALUE SCONN288_DDR506112002KQ
J 0
(-5200 5725);
DISPLAY 0.446809 (-5200 5725);
PAINT SKYBLUE (-5200 5725);
FORCEPROP 1 LAST MATERIAL IO
J 0
(-5200 5550);
DISPLAY 0.468085 (-5200 5550);
PAINT SKYBLUE (-5200 5550);
FORCEPROP 2 LAST CDS_LIB pure_quanta
J 0
(-4600 4375);
DISPLAY INVISIBLE (-4600 4375);
FORCEPROP 1 LAST CDS_LMAN_SYM_OUTLINE -600,1150,600,-1150
J 0
(-4600 4375);
DISPLAY 0.468085 (-4600 4375);
PAINT GREEN (-4600 4375);
DISPLAY INVISIBLE (-4600 4375);
FORCEPROP 1 LAST NEEDS_NO_SIZE TRUE
J 0
(-4600 4375);
DISPLAY 0.723404 (-4600 4375);
PAINT GREEN (-4600 4375);
DISPLAY INVISIBLE (-4600 4375);
FORCEPROP 1 LAST PATH I537
J 0
(-4600 4375);
DISPLAY 0.723404 (-4600 4375);
PAINT GREEN (-4600 4375);
DISPLAY INVISIBLE (-4600 4375);
FORCEPROP 1 LAST PART_NUMBER DFHST8FS479
J 0
(-5200 5625);
DISPLAY 0.468085 (-5200 5625);
PAINT SKYBLUE (-5200 5625);
DISPLAY INVISIBLE (-5200 5625);
FORCEADD SCONN288_DDR506112002KQ..3
(-1450 3700);
FORCEPROP 1 LAST LOCATION J1
J 0
(-1900 5650);
DISPLAY 0.468085 (-1900 5650);
PAINT SKYBLUE (-1900 5650);
FORCEPROP 0 LAST $SEC 3
J 0
(-1900 5825);
DISPLAY 0.680851 (-1900 5825);
PAINT MONO (-1900 5825);
DISPLAY INVISIBLE (-1900 5825);
FORCEPROP 0 LAST CDS_SEC 3
J 0
(-1900 5825);
DISPLAY 0.680851 (-1900 5825);
DISPLAY INVISIBLE (-1900 5825);
FORCEPROP 0 LASTPIN (-850 2100) $PN G1
J 0
(-840 2110);
DISPLAY 0.680851 (-840 2110);
PAINT MONO (-840 2110);
FORCEPROP 0 LASTPIN (-850 2050) $PN G2
J 0
(-840 2060);
DISPLAY 0.680851 (-840 2060);
PAINT MONO (-840 2060);
FORCEPROP 0 LASTPIN (-850 2000) $PN G3
J 0
(-840 2010);
DISPLAY 0.680851 (-840 2010);
PAINT MONO (-840 2010);
FORCEPROP 0 LASTPIN (-2050 5250) $PN 1
J 2
(-2060 5260);
DISPLAY 0.680851 (-2060 5260);
PAINT MONO (-2060 5260);
FORCEPROP 0 LASTPIN (-2050 5300) $PN 145
J 2
(-2060 5310);
DISPLAY 0.680851 (-2060 5310);
PAINT MONO (-2060 5310);
FORCEPROP 0 LASTPIN (-2050 5350) $PN 146
J 2
(-2060 5360);
DISPLAY 0.680851 (-2060 5360);
PAINT MONO (-2060 5360);
FORCEPROP 0 LASTPIN (-850 2200) $PN 6
J 0
(-840 2210);
DISPLAY 0.680851 (-840 2210);
PAINT MONO (-840 2210);
FORCEPROP 0 LASTPIN (-850 2250) $PN 8
J 0
(-840 2260);
DISPLAY 0.680851 (-840 2260);
PAINT MONO (-840 2260);
FORCEPROP 0 LASTPIN (-850 2300) $PN 10
J 0
(-840 2310);
DISPLAY 0.680851 (-840 2310);
PAINT MONO (-840 2310);
FORCEPROP 0 LASTPIN (-850 2350) $PN 13
J 0
(-840 2360);
DISPLAY 0.680851 (-840 2360);
PAINT MONO (-840 2360);
FORCEPROP 0 LASTPIN (-850 2400) $PN 15
J 0
(-840 2410);
DISPLAY 0.680851 (-840 2410);
PAINT MONO (-840 2410);
FORCEPROP 0 LASTPIN (-850 2450) $PN 17
J 0
(-840 2460);
DISPLAY 0.680851 (-840 2460);
PAINT MONO (-840 2460);
FORCEPROP 0 LASTPIN (-850 2500) $PN 19
J 0
(-840 2510);
DISPLAY 0.680851 (-840 2510);
PAINT MONO (-840 2510);
FORCEPROP 0 LASTPIN (-850 2550) $PN 21
J 0
(-840 2560);
DISPLAY 0.680851 (-840 2560);
PAINT MONO (-840 2560);
FORCEPROP 0 LASTPIN (-850 2600) $PN 24
J 0
(-840 2610);
DISPLAY 0.680851 (-840 2610);
PAINT MONO (-840 2610);
FORCEPROP 0 LASTPIN (-850 2650) $PN 26
J 0
(-840 2660);
DISPLAY 0.680851 (-840 2660);
PAINT MONO (-840 2660);
FORCEPROP 0 LASTPIN (-850 2700) $PN 28
J 0
(-840 2710);
DISPLAY 0.680851 (-840 2710);
PAINT MONO (-840 2710);
FORCEPROP 0 LASTPIN (-850 2750) $PN 30
J 0
(-840 2760);
DISPLAY 0.680851 (-840 2760);
PAINT MONO (-840 2760);
FORCEPROP 0 LASTPIN (-850 2800) $PN 32
J 0
(-840 2810);
DISPLAY 0.680851 (-840 2810);
PAINT MONO (-840 2810);
FORCEPROP 0 LASTPIN (-850 2850) $PN 35
J 0
(-840 2860);
DISPLAY 0.680851 (-840 2860);
PAINT MONO (-840 2860);
FORCEPROP 0 LASTPIN (-850 2900) $PN 37
J 0
(-840 2910);
DISPLAY 0.680851 (-840 2910);
PAINT MONO (-840 2910);
FORCEPROP 0 LASTPIN (-850 2950) $PN 39
J 0
(-840 2960);
DISPLAY 0.680851 (-840 2960);
PAINT MONO (-840 2960);
FORCEPROP 0 LASTPIN (-850 3000) $PN 41
J 0
(-840 3010);
DISPLAY 0.680851 (-840 3010);
PAINT MONO (-840 3010);
FORCEPROP 0 LASTPIN (-850 3050) $PN 43
J 0
(-840 3060);
DISPLAY 0.680851 (-840 3060);
PAINT MONO (-840 3060);
FORCEPROP 0 LASTPIN (-850 3100) $PN 46
J 0
(-840 3110);
DISPLAY 0.680851 (-840 3110);
PAINT MONO (-840 3110);
FORCEPROP 0 LASTPIN (-850 3150) $PN 48
J 0
(-840 3160);
DISPLAY 0.680851 (-840 3160);
PAINT MONO (-840 3160);
FORCEPROP 0 LASTPIN (-850 3200) $PN 50
J 0
(-840 3210);
DISPLAY 0.680851 (-840 3210);
PAINT MONO (-840 3210);
FORCEPROP 0 LASTPIN (-850 3250) $PN 52
J 0
(-840 3260);
DISPLAY 0.680851 (-840 3260);
PAINT MONO (-840 3260);
FORCEPROP 0 LASTPIN (-850 3300) $PN 54
J 0
(-840 3310);
DISPLAY 0.680851 (-840 3310);
PAINT MONO (-840 3310);
FORCEPROP 0 LASTPIN (-850 3350) $PN 57
J 0
(-840 3360);
DISPLAY 0.680851 (-840 3360);
PAINT MONO (-840 3360);
FORCEPROP 0 LASTPIN (-850 3400) $PN 59
J 0
(-840 3410);
DISPLAY 0.680851 (-840 3410);
PAINT MONO (-840 3410);
FORCEPROP 0 LASTPIN (-850 3450) $PN 61
J 0
(-840 3460);
DISPLAY 0.680851 (-840 3460);
PAINT MONO (-840 3460);
FORCEPROP 0 LASTPIN (-850 3500) $PN 63
J 0
(-840 3510);
DISPLAY 0.680851 (-840 3510);
PAINT MONO (-840 3510);
FORCEPROP 0 LASTPIN (-850 3550) $PN 65
J 0
(-840 3560);
DISPLAY 0.680851 (-840 3560);
PAINT MONO (-840 3560);
FORCEPROP 0 LASTPIN (-850 3600) $PN 67
J 0
(-840 3610);
DISPLAY 0.680851 (-840 3610);
PAINT MONO (-840 3610);
FORCEPROP 0 LASTPIN (-850 3650) $PN 69
J 0
(-840 3660);
DISPLAY 0.680851 (-840 3660);
PAINT MONO (-840 3660);
FORCEPROP 0 LASTPIN (-850 3700) $PN 71
J 0
(-840 3710);
DISPLAY 0.680851 (-840 3710);
PAINT MONO (-840 3710);
FORCEPROP 0 LASTPIN (-850 3750) $PN 73
J 0
(-840 3760);
DISPLAY 0.680851 (-840 3760);
PAINT MONO (-840 3760);
FORCEPROP 0 LASTPIN (-850 3800) $PN 75
J 0
(-840 3810);
DISPLAY 0.680851 (-840 3810);
PAINT MONO (-840 3810);
FORCEPROP 0 LASTPIN (-850 3850) $PN 77
J 0
(-840 3860);
DISPLAY 0.680851 (-840 3860);
PAINT MONO (-840 3860);
FORCEPROP 0 LASTPIN (-850 3900) $PN 79
J 0
(-840 3910);
DISPLAY 0.680851 (-840 3910);
PAINT MONO (-840 3910);
FORCEPROP 0 LASTPIN (-850 3950) $PN 81
J 0
(-840 3960);
DISPLAY 0.680851 (-840 3960);
PAINT MONO (-840 3960);
FORCEPROP 0 LASTPIN (-850 4000) $PN 83
J 0
(-840 4010);
DISPLAY 0.680851 (-840 4010);
PAINT MONO (-840 4010);
FORCEPROP 0 LASTPIN (-850 4050) $PN 85
J 0
(-840 4060);
DISPLAY 0.680851 (-840 4060);
PAINT MONO (-840 4060);
FORCEPROP 0 LASTPIN (-850 4100) $PN 88
J 0
(-840 4110);
DISPLAY 0.680851 (-840 4110);
PAINT MONO (-840 4110);
FORCEPROP 0 LASTPIN (-850 4150) $PN 90
J 0
(-840 4160);
DISPLAY 0.680851 (-840 4160);
PAINT MONO (-840 4160);
FORCEPROP 0 LASTPIN (-850 4200) $PN 92
J 0
(-840 4210);
DISPLAY 0.680851 (-840 4210);
PAINT MONO (-840 4210);
FORCEPROP 0 LASTPIN (-850 4250) $PN 95
J 0
(-840 4260);
DISPLAY 0.680851 (-840 4260);
PAINT MONO (-840 4260);
FORCEPROP 0 LASTPIN (-850 4300) $PN 97
J 0
(-840 4310);
DISPLAY 0.680851 (-840 4310);
PAINT MONO (-840 4310);
FORCEPROP 0 LASTPIN (-850 4350) $PN 99
J 0
(-840 4360);
DISPLAY 0.680851 (-840 4360);
PAINT MONO (-840 4360);
FORCEPROP 0 LASTPIN (-850 4400) $PN 101
J 0
(-840 4410);
DISPLAY 0.680851 (-840 4410);
PAINT MONO (-840 4410);
FORCEPROP 0 LASTPIN (-850 4450) $PN 103
J 0
(-840 4460);
DISPLAY 0.680851 (-840 4460);
PAINT MONO (-840 4460);
FORCEPROP 0 LASTPIN (-850 4500) $PN 106
J 0
(-840 4510);
DISPLAY 0.680851 (-840 4510);
PAINT MONO (-840 4510);
FORCEPROP 0 LASTPIN (-850 4550) $PN 108
J 0
(-840 4560);
DISPLAY 0.680851 (-840 4560);
PAINT MONO (-840 4560);
FORCEPROP 0 LASTPIN (-850 4600) $PN 110
J 0
(-840 4610);
DISPLAY 0.680851 (-840 4610);
PAINT MONO (-840 4610);
FORCEPROP 0 LASTPIN (-850 4650) $PN 112
J 0
(-840 4660);
DISPLAY 0.680851 (-840 4660);
PAINT MONO (-840 4660);
FORCEPROP 0 LASTPIN (-850 4700) $PN 114
J 0
(-840 4710);
DISPLAY 0.680851 (-840 4710);
PAINT MONO (-840 4710);
FORCEPROP 0 LASTPIN (-850 4750) $PN 117
J 0
(-840 4760);
DISPLAY 0.680851 (-840 4760);
PAINT MONO (-840 4760);
FORCEPROP 0 LASTPIN (-850 4800) $PN 119
J 0
(-840 4810);
DISPLAY 0.680851 (-840 4810);
PAINT MONO (-840 4810);
FORCEPROP 0 LASTPIN (-850 4850) $PN 121
J 0
(-840 4860);
DISPLAY 0.680851 (-840 4860);
PAINT MONO (-840 4860);
FORCEPROP 0 LASTPIN (-850 4900) $PN 123
J 0
(-840 4910);
DISPLAY 0.680851 (-840 4910);
PAINT MONO (-840 4910);
FORCEPROP 0 LASTPIN (-850 4950) $PN 125
J 0
(-840 4960);
DISPLAY 0.680851 (-840 4960);
PAINT MONO (-840 4960);
FORCEPROP 0 LASTPIN (-850 5000) $PN 128
J 0
(-840 5010);
DISPLAY 0.680851 (-840 5010);
PAINT MONO (-840 5010);
FORCEPROP 0 LASTPIN (-850 5050) $PN 130
J 0
(-840 5060);
DISPLAY 0.680851 (-840 5060);
PAINT MONO (-840 5060);
FORCEPROP 0 LASTPIN (-850 5100) $PN 132
J 0
(-840 5110);
DISPLAY 0.680851 (-840 5110);
PAINT MONO (-840 5110);
FORCEPROP 0 LASTPIN (-850 5150) $PN 134
J 0
(-840 5160);
DISPLAY 0.680851 (-840 5160);
PAINT MONO (-840 5160);
FORCEPROP 0 LASTPIN (-850 5200) $PN 136
J 0
(-840 5210);
DISPLAY 0.680851 (-840 5210);
PAINT MONO (-840 5210);
FORCEPROP 0 LASTPIN (-850 5250) $PN 139
J 0
(-840 5260);
DISPLAY 0.680851 (-840 5260);
PAINT MONO (-840 5260);
FORCEPROP 0 LASTPIN (-850 5300) $PN 141
J 0
(-840 5310);
DISPLAY 0.680851 (-840 5310);
PAINT MONO (-840 5310);
FORCEPROP 0 LASTPIN (-850 5350) $PN 143
J 0
(-840 5360);
DISPLAY 0.680851 (-840 5360);
PAINT MONO (-840 5360);
FORCEPROP 0 LASTPIN (-2050 2100) $PN 151
J 2
(-2060 2110);
DISPLAY 0.680851 (-2060 2110);
PAINT MONO (-2060 2110);
FORCEPROP 0 LASTPIN (-2050 2150) $PN 153
J 2
(-2060 2160);
DISPLAY 0.680851 (-2060 2160);
PAINT MONO (-2060 2160);
FORCEPROP 0 LASTPIN (-2050 2200) $PN 155
J 2
(-2060 2210);
DISPLAY 0.680851 (-2060 2210);
PAINT MONO (-2060 2210);
FORCEPROP 0 LASTPIN (-2050 2250) $PN 158
J 2
(-2060 2260);
DISPLAY 0.680851 (-2060 2260);
PAINT MONO (-2060 2260);
FORCEPROP 0 LASTPIN (-2050 2300) $PN 160
J 2
(-2060 2310);
DISPLAY 0.680851 (-2060 2310);
PAINT MONO (-2060 2310);
FORCEPROP 0 LASTPIN (-2050 2350) $PN 162
J 2
(-2060 2360);
DISPLAY 0.680851 (-2060 2360);
PAINT MONO (-2060 2360);
FORCEPROP 0 LASTPIN (-2050 2400) $PN 164
J 2
(-2060 2410);
DISPLAY 0.680851 (-2060 2410);
PAINT MONO (-2060 2410);
FORCEPROP 0 LASTPIN (-2050 2450) $PN 166
J 2
(-2060 2460);
DISPLAY 0.680851 (-2060 2460);
PAINT MONO (-2060 2460);
FORCEPROP 0 LASTPIN (-2050 2500) $PN 169
J 2
(-2060 2510);
DISPLAY 0.680851 (-2060 2510);
PAINT MONO (-2060 2510);
FORCEPROP 0 LASTPIN (-2050 2550) $PN 171
J 2
(-2060 2560);
DISPLAY 0.680851 (-2060 2560);
PAINT MONO (-2060 2560);
FORCEPROP 0 LASTPIN (-2050 2600) $PN 173
J 2
(-2060 2610);
DISPLAY 0.680851 (-2060 2610);
PAINT MONO (-2060 2610);
FORCEPROP 0 LASTPIN (-2050 2650) $PN 175
J 2
(-2060 2660);
DISPLAY 0.680851 (-2060 2660);
PAINT MONO (-2060 2660);
FORCEPROP 0 LASTPIN (-2050 2700) $PN 177
J 2
(-2060 2710);
DISPLAY 0.680851 (-2060 2710);
PAINT MONO (-2060 2710);
FORCEPROP 0 LASTPIN (-2050 2750) $PN 180
J 2
(-2060 2760);
DISPLAY 0.680851 (-2060 2760);
PAINT MONO (-2060 2760);
FORCEPROP 0 LASTPIN (-2050 2800) $PN 182
J 2
(-2060 2810);
DISPLAY 0.680851 (-2060 2810);
PAINT MONO (-2060 2810);
FORCEPROP 0 LASTPIN (-2050 2850) $PN 184
J 2
(-2060 2860);
DISPLAY 0.680851 (-2060 2860);
PAINT MONO (-2060 2860);
FORCEPROP 0 LASTPIN (-2050 2900) $PN 186
J 2
(-2060 2910);
DISPLAY 0.680851 (-2060 2910);
PAINT MONO (-2060 2910);
FORCEPROP 0 LASTPIN (-2050 2950) $PN 188
J 2
(-2060 2960);
DISPLAY 0.680851 (-2060 2960);
PAINT MONO (-2060 2960);
FORCEPROP 0 LASTPIN (-2050 3000) $PN 191
J 2
(-2060 3010);
DISPLAY 0.680851 (-2060 3010);
PAINT MONO (-2060 3010);
FORCEPROP 0 LASTPIN (-2050 3050) $PN 193
J 2
(-2060 3060);
DISPLAY 0.680851 (-2060 3060);
PAINT MONO (-2060 3060);
FORCEPROP 0 LASTPIN (-2050 3100) $PN 195
J 2
(-2060 3110);
DISPLAY 0.680851 (-2060 3110);
PAINT MONO (-2060 3110);
FORCEPROP 0 LASTPIN (-2050 3150) $PN 197
J 2
(-2060 3160);
DISPLAY 0.680851 (-2060 3160);
PAINT MONO (-2060 3160);
FORCEPROP 0 LASTPIN (-2050 3200) $PN 199
J 2
(-2060 3210);
DISPLAY 0.680851 (-2060 3210);
PAINT MONO (-2060 3210);
FORCEPROP 0 LASTPIN (-2050 3250) $PN 202
J 2
(-2060 3260);
DISPLAY 0.680851 (-2060 3260);
PAINT MONO (-2060 3260);
FORCEPROP 0 LASTPIN (-2050 3300) $PN 204
J 2
(-2060 3310);
DISPLAY 0.680851 (-2060 3310);
PAINT MONO (-2060 3310);
FORCEPROP 0 LASTPIN (-2050 3350) $PN 206
J 2
(-2060 3360);
DISPLAY 0.680851 (-2060 3360);
PAINT MONO (-2060 3360);
FORCEPROP 0 LASTPIN (-2050 3400) $PN 208
J 2
(-2060 3410);
DISPLAY 0.680851 (-2060 3410);
PAINT MONO (-2060 3410);
FORCEPROP 0 LASTPIN (-2050 3450) $PN 210
J 2
(-2060 3460);
DISPLAY 0.680851 (-2060 3460);
PAINT MONO (-2060 3460);
FORCEPROP 0 LASTPIN (-2050 3500) $PN 212
J 2
(-2060 3510);
DISPLAY 0.680851 (-2060 3510);
PAINT MONO (-2060 3510);
FORCEPROP 0 LASTPIN (-2050 3550) $PN 214
J 2
(-2060 3560);
DISPLAY 0.680851 (-2060 3560);
PAINT MONO (-2060 3560);
FORCEPROP 0 LASTPIN (-2050 3600) $PN 216
J 2
(-2060 3610);
DISPLAY 0.680851 (-2060 3610);
PAINT MONO (-2060 3610);
FORCEPROP 0 LASTPIN (-2050 3650) $PN 219
J 2
(-2060 3660);
DISPLAY 0.680851 (-2060 3660);
PAINT MONO (-2060 3660);
FORCEPROP 0 LASTPIN (-2050 3700) $PN 222
J 2
(-2060 3710);
DISPLAY 0.680851 (-2060 3710);
PAINT MONO (-2060 3710);
FORCEPROP 0 LASTPIN (-2050 3750) $PN 224
J 2
(-2060 3760);
DISPLAY 0.680851 (-2060 3760);
PAINT MONO (-2060 3760);
FORCEPROP 0 LASTPIN (-2050 3800) $PN 226
J 2
(-2060 3810);
DISPLAY 0.680851 (-2060 3810);
PAINT MONO (-2060 3810);
FORCEPROP 0 LASTPIN (-2050 3850) $PN 228
J 2
(-2060 3860);
DISPLAY 0.680851 (-2060 3860);
PAINT MONO (-2060 3860);
FORCEPROP 0 LASTPIN (-2050 3900) $PN 230
J 2
(-2060 3910);
DISPLAY 0.680851 (-2060 3910);
PAINT MONO (-2060 3910);
FORCEPROP 0 LASTPIN (-2050 3950) $PN 233
J 2
(-2060 3960);
DISPLAY 0.680851 (-2060 3960);
PAINT MONO (-2060 3960);
FORCEPROP 0 LASTPIN (-2050 4000) $PN 235
J 2
(-2060 4010);
DISPLAY 0.680851 (-2060 4010);
PAINT MONO (-2060 4010);
FORCEPROP 0 LASTPIN (-2050 4050) $PN 237
J 2
(-2060 4060);
DISPLAY 0.680851 (-2060 4060);
PAINT MONO (-2060 4060);
FORCEPROP 0 LASTPIN (-2050 4100) $PN 240
J 2
(-2060 4110);
DISPLAY 0.680851 (-2060 4110);
PAINT MONO (-2060 4110);
FORCEPROP 0 LASTPIN (-2050 4150) $PN 242
J 2
(-2060 4160);
DISPLAY 0.680851 (-2060 4160);
PAINT MONO (-2060 4160);
FORCEPROP 0 LASTPIN (-2050 4200) $PN 244
J 2
(-2060 4210);
DISPLAY 0.680851 (-2060 4210);
PAINT MONO (-2060 4210);
FORCEPROP 0 LASTPIN (-2050 4250) $PN 246
J 2
(-2060 4260);
DISPLAY 0.680851 (-2060 4260);
PAINT MONO (-2060 4260);
FORCEPROP 0 LASTPIN (-2050 4300) $PN 248
J 2
(-2060 4310);
DISPLAY 0.680851 (-2060 4310);
PAINT MONO (-2060 4310);
FORCEPROP 0 LASTPIN (-2050 4350) $PN 251
J 2
(-2060 4360);
DISPLAY 0.680851 (-2060 4360);
PAINT MONO (-2060 4360);
FORCEPROP 0 LASTPIN (-2050 4400) $PN 253
J 2
(-2060 4410);
DISPLAY 0.680851 (-2060 4410);
PAINT MONO (-2060 4410);
FORCEPROP 0 LASTPIN (-2050 4450) $PN 255
J 2
(-2060 4460);
DISPLAY 0.680851 (-2060 4460);
PAINT MONO (-2060 4460);
FORCEPROP 0 LASTPIN (-2050 4500) $PN 257
J 2
(-2060 4510);
DISPLAY 0.680851 (-2060 4510);
PAINT MONO (-2060 4510);
FORCEPROP 0 LASTPIN (-2050 4550) $PN 259
J 2
(-2060 4560);
DISPLAY 0.680851 (-2060 4560);
PAINT MONO (-2060 4560);
FORCEPROP 0 LASTPIN (-2050 4600) $PN 262
J 2
(-2060 4610);
DISPLAY 0.680851 (-2060 4610);
PAINT MONO (-2060 4610);
FORCEPROP 0 LASTPIN (-2050 4650) $PN 264
J 2
(-2060 4660);
DISPLAY 0.680851 (-2060 4660);
PAINT MONO (-2060 4660);
FORCEPROP 0 LASTPIN (-2050 4700) $PN 266
J 2
(-2060 4710);
DISPLAY 0.680851 (-2060 4710);
PAINT MONO (-2060 4710);
FORCEPROP 0 LASTPIN (-2050 4750) $PN 268
J 2
(-2060 4760);
DISPLAY 0.680851 (-2060 4760);
PAINT MONO (-2060 4760);
FORCEPROP 0 LASTPIN (-2050 4800) $PN 270
J 2
(-2060 4810);
DISPLAY 0.680851 (-2060 4810);
PAINT MONO (-2060 4810);
FORCEPROP 0 LASTPIN (-2050 4850) $PN 273
J 2
(-2060 4860);
DISPLAY 0.680851 (-2060 4860);
PAINT MONO (-2060 4860);
FORCEPROP 0 LASTPIN (-2050 4900) $PN 275
J 2
(-2060 4910);
DISPLAY 0.680851 (-2060 4910);
PAINT MONO (-2060 4910);
FORCEPROP 0 LASTPIN (-2050 4950) $PN 277
J 2
(-2060 4960);
DISPLAY 0.680851 (-2060 4960);
PAINT MONO (-2060 4960);
FORCEPROP 0 LASTPIN (-2050 5000) $PN 279
J 2
(-2060 5010);
DISPLAY 0.680851 (-2060 5010);
PAINT MONO (-2060 5010);
FORCEPROP 0 LASTPIN (-2050 5050) $PN 281
J 2
(-2060 5060);
DISPLAY 0.680851 (-2060 5060);
PAINT MONO (-2060 5060);
FORCEPROP 0 LASTPIN (-2050 5100) $PN 284
J 2
(-2060 5110);
DISPLAY 0.680851 (-2060 5110);
PAINT MONO (-2060 5110);
FORCEPROP 0 LASTPIN (-2050 5150) $PN 286
J 2
(-2060 5160);
DISPLAY 0.680851 (-2060 5160);
PAINT MONO (-2060 5160);
FORCEPROP 0 LASTPIN (-2050 5200) $PN 288
J 2
(-2060 5210);
DISPLAY 0.680851 (-2060 5210);
PAINT MONO (-2060 5210);
FORCEPROP 2 LAST VALUE SCONN288_DDR506112002KQ
J 0
(-1900 5725);
DISPLAY 0.446809 (-1900 5725);
PAINT SKYBLUE (-1900 5725);
FORCEPROP 1 LAST MATERIAL IO
J 0
(-1900 5525);
DISPLAY 0.468085 (-1900 5525);
PAINT SKYBLUE (-1900 5525);
FORCEPROP 2 LAST PART_TYPE SMLF
J 0
(-1900 5775);
DISPLAY 0.680851 (-1900 5775);
FORCEPROP 2 LAST CDS_LIB pure_quanta
J 0
(-1450 3700);
DISPLAY INVISIBLE (-1450 3700);
FORCEPROP 1 LAST CDS_LMAN_SYM_OUTLINE -450,1800,450,-1750
J 0
(-1450 3700);
DISPLAY 0.468085 (-1450 3700);
PAINT GREEN (-1450 3700);
DISPLAY INVISIBLE (-1450 3700);
FORCEPROP 1 LAST NEEDS_NO_SIZE TRUE
J 0
(-1450 3700);
DISPLAY 0.723404 (-1450 3700);
PAINT GREEN (-1450 3700);
DISPLAY INVISIBLE (-1450 3700);
FORCEPROP 1 LAST PATH I538
J 0
(-1450 3700);
DISPLAY 0.723404 (-1450 3700);
PAINT GREEN (-1450 3700);
DISPLAY INVISIBLE (-1450 3700);
FORCEPROP 1 LAST PART_NUMBER DFHST8FS479
J 0
(-1900 5600);
DISPLAY 0.468085 (-1900 5600);
PAINT SKYBLUE (-1900 5600);
DISPLAY INVISIBLE (-1900 5600);
FORCEADD Q_RES..1
(-7775 2700);
FORCEPROP 1 LAST LOCATION R1568
J 0
(-7825 2725);
DISPLAY 0.510638 (-7825 2725);
PAINT SKYBLUE (-7825 2725);
FORCEPROP 0 LAST $SEC 1
J 0
(-7825 2775);
DISPLAY 0.680851 (-7825 2775);
PAINT MONO (-7825 2775);
DISPLAY INVISIBLE (-7825 2775);
FORCEPROP 0 LAST CDS_SEC 1
J 0
(-7825 2775);
DISPLAY 0.680851 (-7825 2775);
DISPLAY INVISIBLE (-7825 2775);
FORCEPROP 1 LASTPIN (-7875 2700) $PN 1
J 0
(-7863 2712);
DISPLAY 0.787234 (-7863 2712);
PAINT MONO (-7863 2712);
FORCEPROP 1 LASTPIN (-7675 2700) $PN 2
J 0
(-7713 2712);
DISPLAY 0.787234 (-7713 2712);
PAINT MONO (-7713 2712);
FORCEPROP 1 LAST VALUE 49.9
J 2
(-7725 2650);
DISPLAY 0.510638 (-7725 2650);
PAINT SKYBLUE (-7725 2650);
FORCEPROP 2 LAST CDS_LIB pure_quanta
J 0
(-7775 2700);
DISPLAY INVISIBLE (-7775 2700);
FORCEPROP 1 LAST MATERIAL CHIP
J 0
(-7775 2550);
DISPLAY 0.978723 (-7775 2550);
DISPLAY INVISIBLE (-7775 2550);
FORCEPROP 1 LAST PACK_TYPE 0402LF
J 0
(-7525 2550);
DISPLAY 0.978723 (-7525 2550);
DISPLAY INVISIBLE (-7525 2550);
FORCEPROP 1 LAST WATTAGE 1/16W
J 2
(-7800 2550);
DISPLAY 0.978723 (-7800 2550);
DISPLAY INVISIBLE (-7800 2550);
FORCEPROP 1 LAST TOLERANCE 1%
J 0
(-7775 2600);
DISPLAY 0.978723 (-7775 2600);
DISPLAY INVISIBLE (-7775 2600);
FORCEPROP 1 LAST PATH I539
J 0
(-7825 2850);
DISPLAY 0.978723 (-7825 2850);
PAINT WHITE (-7825 2850);
DISPLAY INVISIBLE (-7825 2850);
FORCEPROP 1 LAST PART_NUMBER CS04992FB07
J 0
(-7825 2800);
DISPLAY 0.978723 (-7825 2800);
DISPLAY INVISIBLE (-7825 2800);
FORCEADD Q_RES..2
(-8750 1375);
FORCEPROP 1 LAST LOCATION R8037
J 0
(-8705 1500);
DISPLAY 0.978723 (-8705 1500);
FORCEPROP 0 LAST $SEC 1
J 0
(-8700 1550);
DISPLAY 0.680851 (-8700 1550);
PAINT MONO (-8700 1550);
DISPLAY INVISIBLE (-8700 1550);
FORCEPROP 0 LAST CDS_SEC 1
J 0
(-8700 1550);
DISPLAY 0.680851 (-8700 1550);
DISPLAY INVISIBLE (-8700 1550);
FORCEPROP 1 LASTPIN (-8750 1475) $PN 1
J 0
(-8745 1437);
DISPLAY 0.787234 (-8745 1437);
PAINT MONO (-8745 1437);
FORCEPROP 1 LASTPIN (-8750 1275) $PN 2
J 0
(-8745 1285);
DISPLAY 0.787234 (-8745 1285);
PAINT MONO (-8745 1285);
FORCEPROP 1 LAST WATTAGE 1/16W
J 0
(-8710 1350);
DISPLAY 0.978723 (-8710 1350);
FORCEPROP 1 LAST MATERIAL CHIP
J 0
(-8710 1300);
DISPLAY 0.978723 (-8710 1300);
FORCEPROP 1 LAST VALUE 10K
J 0
(-8705 1450);
DISPLAY 0.978723 (-8705 1450);
FORCEPROP 1 LAST TOLERANCE 1%
J 0
(-8705 1400);
DISPLAY 0.978723 (-8705 1400);
FORCEPROP 1 LAST PACK_TYPE 0402LF
J 0
(-8710 1200);
DISPLAY 0.978723 (-8710 1200);
FORCEPROP 2 LAST CDS_LIB pure_quanta
J 0
(-8750 1375);
DISPLAY INVISIBLE (-8750 1375);
FORCEPROP 1 LAST PATH I540
J 0
(-8700 1550);
DISPLAY 0.978723 (-8700 1550);
PAINT WHITE (-8700 1550);
DISPLAY INVISIBLE (-8700 1550);
FORCEPROP 1 LAST PART_NUMBER CS31002FB08
J 0
(-8710 1250);
DISPLAY 0.978723 (-8710 1250);
DISPLAY INVISIBLE (-8710 1250);
FORCEADD VCC_CORE..1
(-8750 1675);
FORCEPROP 3 LASTPIN (-8750 1625) SIG_NAME P3V3_AUX\g
J 0
(-8740 1635);
DISPLAY 0.659574 (-8740 1635);
PAINT MONO (-8740 1635);
DISPLAY INVISIBLE (-8740 1635);
FORCEPROP 1 LAST HDL_POWER P3V3_AUX
J 1
(-8750 1725);
DISPLAY 0.489362 (-8750 1725);
PAINT GREEN (-8750 1725);
FORCEPROP 2 LAST CDS_LIB mstr_symbols
J 0
(-8750 1675);
DISPLAY INVISIBLE (-8750 1675);
FORCEPROP 0 LAST VOLTAGE 3.3
J 0
(-9025 1825);
DISPLAY 1.021277 (-9025 1825);
PAINT SKYBLUE (-9025 1825);
DISPLAY INVISIBLE (-9025 1825);
FORCEPROP 2 LAST ROOM PVCCINFAON_CPU0_CTRL
J 0
(-8750 1775);
DISPLAY 0.808511 (-8750 1775);
PAINT RED (-8750 1775);
DISPLAY INVISIBLE (-8750 1775);
FORCEPROP 1 LAST PATH I541
J 0
(-8700 1700);
DISPLAY 0.872340 (-8700 1700);
PAINT AQUA (-8700 1700);
DISPLAY INVISIBLE (-8700 1700);
FORCEADD OFFPAGE..2
(-7725 975);
FORCEPROP 2 LAST $XR5 91 
J 0
(-7086 975);
DISPLAY 0.638298 (-7086 975);
PAINT MONO (-7086 975);
FORCEPROP 2 LAST $XR4 90 
J 0
(-7176 975);
DISPLAY 0.638298 (-7176 975);
PAINT MONO (-7176 975);
FORCEPROP 2 LAST $XR3 89 
J 0
(-7266 975);
DISPLAY 0.638298 (-7266 975);
PAINT MONO (-7266 975);
FORCEPROP 2 LAST $XR2 88 
J 0
(-7356 975);
DISPLAY 0.638298 (-7356 975);
PAINT MONO (-7356 975);
FORCEPROP 2 LAST $XR1 87 
J 0
(-7446 975);
DISPLAY 0.638298 (-7446 975);
PAINT MONO (-7446 975);
FORCEPROP 2 LAST $XR0 86 
J 0
(-7536 975);
DISPLAY 0.638298 (-7536 975);
PAINT MONO (-7536 975);
FORCEPROP 2 LAST CDS_LIB mstr_standard
J 0
(-7725 975);
DISPLAY INVISIBLE (-7725 975);
FORCEPROP 1 LAST OFFPAGE TRUE
J 0
(-7400 850);
DISPLAY 0.723404 (-7400 850);
PAINT GREEN (-7400 850);
DISPLAY INVISIBLE (-7400 850);
FORCEPROP 1 LAST COMMENT_BODY TRUE
J 0
(-7770 880);
DISPLAY 0.872340 (-7770 880);
PAINT GREEN (-7770 880);
DISPLAY INVISIBLE (-7770 880);
FORCEPROP 2 LAST PATH I542
J 0
(-7550 1050);
DISPLAY 0.680851 (-7550 1050);
DISPLAY INVISIBLE (-7550 1050);
FORCEADD Q_RES..1
(-4525 900);
FORCEPROP 1 LAST LOCATION R8080
J 0
(-4575 950);
DISPLAY 0.978723 (-4575 950);
FORCEPROP 0 LAST $SEC 1
J 0
(-4575 1000);
DISPLAY 0.680851 (-4575 1000);
PAINT MONO (-4575 1000);
DISPLAY INVISIBLE (-4575 1000);
FORCEPROP 0 LAST CDS_SEC 1
J 0
(-4575 1000);
DISPLAY 0.680851 (-4575 1000);
DISPLAY INVISIBLE (-4575 1000);
FORCEPROP 1 LASTPIN (-4625 900) $PN 1
J 0
(-4613 912);
DISPLAY 0.787234 (-4613 912);
PAINT MONO (-4613 912);
FORCEPROP 1 LASTPIN (-4425 900) $PN 2
J 0
(-4463 912);
DISPLAY 0.787234 (-4463 912);
PAINT MONO (-4463 912);
FORCEPROP 1 LAST PACK_TYPE 0402LF
J 0
(-4275 750);
DISPLAY 0.978723 (-4275 750);
FORCEPROP 1 LAST MATERIAL CHIP
J 0
(-4525 750);
DISPLAY 0.978723 (-4525 750);
FORCEPROP 1 LAST WATTAGE 1/16W
J 2
(-4550 750);
DISPLAY 0.978723 (-4550 750);
FORCEPROP 1 LAST TOLERANCE 5%
J 0
(-4525 800);
DISPLAY 0.978723 (-4525 800);
FORCEPROP 1 LAST VALUE 0
J 2
(-4550 800);
DISPLAY 0.978723 (-4550 800);
FORCEPROP 2 LAST CDS_LIB pure_quanta
J 0
(-4525 900);
DISPLAY INVISIBLE (-4525 900);
FORCEPROP 1 LAST PATH I544
J 0
(-4575 1050);
DISPLAY 0.978723 (-4575 1050);
PAINT WHITE (-4575 1050);
DISPLAY INVISIBLE (-4575 1050);
FORCEPROP 1 LAST PART_NUMBER CS00002JB13
J 0
(-4750 700);
DISPLAY 0.978723 (-4750 700);
DISPLAY INVISIBLE (-4750 700);
FORCEADD Q_RES..1
(-3100 900);
FORCEPROP 1 LAST LOCATION R8081
J 0
(-3150 950);
DISPLAY 0.978723 (-3150 950);
FORCEPROP 0 LAST $SEC 1
J 0
(-3150 1000);
DISPLAY 0.680851 (-3150 1000);
PAINT MONO (-3150 1000);
DISPLAY INVISIBLE (-3150 1000);
FORCEPROP 0 LAST CDS_SEC 1
J 0
(-3150 1000);
DISPLAY 0.680851 (-3150 1000);
DISPLAY INVISIBLE (-3150 1000);
FORCEPROP 1 LASTPIN (-3200 900) $PN 1
J 0
(-3188 912);
DISPLAY 0.787234 (-3188 912);
PAINT MONO (-3188 912);
FORCEPROP 1 LASTPIN (-3000 900) $PN 2
J 0
(-3038 912);
DISPLAY 0.787234 (-3038 912);
PAINT MONO (-3038 912);
FORCEPROP 1 LAST MATERIAL CHIP
J 0
(-3100 750);
DISPLAY 0.978723 (-3100 750);
FORCEPROP 1 LAST PACK_TYPE 0402LF
J 0
(-2850 750);
DISPLAY 0.978723 (-2850 750);
FORCEPROP 1 LAST WATTAGE 1/16W
J 2
(-3125 750);
DISPLAY 0.978723 (-3125 750);
FORCEPROP 1 LAST TOLERANCE 5%
J 0
(-3100 800);
DISPLAY 0.978723 (-3100 800);
FORCEPROP 1 LAST VALUE 0
J 2
(-3125 800);
DISPLAY 0.978723 (-3125 800);
FORCEPROP 2 LAST CDS_LIB pure_quanta
J 0
(-3100 900);
DISPLAY INVISIBLE (-3100 900);
FORCEPROP 1 LAST PATH I545
J 0
(-3150 1050);
DISPLAY 0.978723 (-3150 1050);
PAINT WHITE (-3150 1050);
DISPLAY INVISIBLE (-3150 1050);
FORCEPROP 1 LAST PART_NUMBER CS00002JB13
J 0
(-3300 675);
DISPLAY 0.978723 (-3300 675);
DISPLAY INVISIBLE (-3300 675);
FORCEADD Q_RES..1
(-4950 1375);
FORCEPROP 1 LAST LOCATION R8082
J 0
(-5000 1425);
DISPLAY 0.978723 (-5000 1425);
FORCEPROP 0 LAST $SEC 1
J 0
(-5000 1550);
DISPLAY 0.680851 (-5000 1550);
PAINT MONO (-5000 1550);
DISPLAY INVISIBLE (-5000 1550);
FORCEPROP 0 LAST CDS_SEC 1
J 0
(-5000 1550);
DISPLAY 0.680851 (-5000 1550);
DISPLAY INVISIBLE (-5000 1550);
FORCEPROP 1 LASTPIN (-5050 1375) $PN 1
J 0
(-5038 1387);
DISPLAY 0.787234 (-5038 1387);
PAINT MONO (-5038 1387);
FORCEPROP 1 LASTPIN (-4850 1375) $PN 2
J 0
(-4888 1387);
DISPLAY 0.787234 (-4888 1387);
PAINT MONO (-4888 1387);
FORCEPROP 1 LAST VALUE 10K
J 2
(-4975 1275);
DISPLAY 0.978723 (-4975 1275);
FORCEPROP 1 LAST TOLERANCE 1%
J 0
(-4950 1275);
DISPLAY 0.978723 (-4950 1275);
FORCEPROP 1 LAST MATERIAL EMPTY
J 0
(-4950 1225);
DISPLAY 0.978723 (-4950 1225);
PAINT RED (-4950 1225);
FORCEPROP 1 LAST PACK_TYPE 0402LF
J 0
(-4700 1225);
DISPLAY 0.978723 (-4700 1225);
FORCEPROP 1 LAST WATTAGE 1/16W
J 2
(-4975 1225);
DISPLAY 0.978723 (-4975 1225);
FORCEPROP 2 LAST CDS_LIB pure_quanta
J 0
(-4950 1375);
DISPLAY INVISIBLE (-4950 1375);
FORCEPROP 1 LAST PATH I547
J 0
(-5000 1525);
DISPLAY 0.978723 (-5000 1525);
PAINT WHITE (-5000 1525);
DISPLAY INVISIBLE (-5000 1525);
FORCEPROP 1 LAST PART_NUMBER CS31002FB08
J 0
(-5000 1500);
DISPLAY 0.978723 (-5000 1500);
DISPLAY INVISIBLE (-5000 1500);
FORCEADD VCC_CORE..1
(-5550 1575);
FORCEPROP 3 LASTPIN (-5550 1525) SIG_NAME P3V3_AUX\g
J 0
(-5540 1535);
DISPLAY 0.659574 (-5540 1535);
PAINT MONO (-5540 1535);
DISPLAY INVISIBLE (-5540 1535);
FORCEPROP 1 LAST HDL_POWER P3V3_AUX
J 1
(-5550 1625);
DISPLAY 0.489362 (-5550 1625);
PAINT GREEN (-5550 1625);
FORCEPROP 2 LAST ROOM PVCCINFAON_CPU0_CTRL
J 0
(-5550 1675);
DISPLAY 0.808511 (-5550 1675);
PAINT RED (-5550 1675);
DISPLAY INVISIBLE (-5550 1675);
FORCEPROP 0 LAST VOLTAGE 3.3
J 0
(-5825 1725);
DISPLAY 1.021277 (-5825 1725);
PAINT SKYBLUE (-5825 1725);
DISPLAY INVISIBLE (-5825 1725);
FORCEPROP 2 LAST CDS_LIB mstr_symbols
J 0
(-5550 1575);
DISPLAY INVISIBLE (-5550 1575);
FORCEPROP 1 LAST PATH I548
J 0
(-5500 1600);
DISPLAY 0.872340 (-5500 1600);
PAINT AQUA (-5500 1600);
DISPLAY INVISIBLE (-5500 1600);
FORCEADD SCHOTTKY_12..1
(-3000 1350);
FORCEPROP 1 LAST LOCATION D8003
J 0
(-3075 1525);
DISPLAY 0.723404 (-3075 1525);
PAINT GREEN (-3075 1525);
FORCEPROP 2 LAST SEC 1
J 0
(-3075 1675);
DISPLAY 0.680851 (-3075 1675);
PAINT MONO (-3075 1675);
DISPLAY INVISIBLE (-3075 1675);
FORCEPROP 2 LASTPIN (-3125 1350) $PN 1
J 2
(-3135 1360);
DISPLAY 0.680851 (-3135 1360);
PAINT MONO (-3135 1360);
FORCEPROP 2 LASTPIN (-2875 1350) $PN 2
J 0
(-2865 1360);
DISPLAY 0.680851 (-2865 1360);
PAINT MONO (-2865 1360);
FORCEPROP 2 LAST VALUE B0530WS7F
J 0
(-3075 1575);
DISPLAY 0.680851 (-3075 1575);
FORCEPROP 2 LAST PART_TYPE SMLF
J 0
(-3075 1625);
DISPLAY 0.680851 (-3075 1625);
FORCEPROP 1 LAST MATERIAL EMPTY
J 0
(-3075 1425);
DISPLAY 0.723404 (-3075 1425);
PAINT RED (-3075 1425);
FORCEPROP 1 LAST NEEDS_NO_SIZE TRUE
J 0
(-2925 1300);
DISPLAY 0.468085 (-2925 1300);
PAINT GREEN (-2925 1300);
DISPLAY INVISIBLE (-2925 1300);
FORCEPROP 2 LAST SEC_TYPE 
J 0
(-3075 1675);
DISPLAY 0.680851 (-3075 1675);
DISPLAY INVISIBLE (-3075 1675);
FORCEPROP 1 LAST CDS_LMAN_SYM_OUTLINE -75,50,75,-50
J 0
(-3000 1350);
DISPLAY 0.468085 (-3000 1350);
PAINT GREEN (-3000 1350);
DISPLAY INVISIBLE (-3000 1350);
FORCEPROP 2 LAST CDS_LIB pure_quanta
J 0
(-3000 1350);
DISPLAY INVISIBLE (-3000 1350);
FORCEPROP 1 LAST PATH I549
J 0
(-3000 1350);
DISPLAY 0.723404 (-3000 1350);
PAINT GREEN (-3000 1350);
DISPLAY INVISIBLE (-3000 1350);
FORCEPROP 1 LAST PART_NUMBER BC000530Z41
J 0
(-3075 1475);
DISPLAY 0.723404 (-3075 1475);
PAINT GREEN (-3075 1475);
DISPLAY INVISIBLE (-3075 1475);
FORCEADD VCC_CORE..1
(-2325 1475);
FORCEPROP 3 LASTPIN (-2325 1425) SIG_NAME P3V3_AUX\g
J 0
(-2315 1435);
DISPLAY 0.659574 (-2315 1435);
PAINT MONO (-2315 1435);
DISPLAY INVISIBLE (-2315 1435);
FORCEPROP 1 LAST HDL_POWER P3V3_AUX
J 1
(-2325 1525);
DISPLAY 0.489362 (-2325 1525);
PAINT GREEN (-2325 1525);
FORCEPROP 0 LAST VOLTAGE 3.3
J 0
(-2600 1625);
DISPLAY 1.021277 (-2600 1625);
PAINT SKYBLUE (-2600 1625);
DISPLAY INVISIBLE (-2600 1625);
FORCEPROP 2 LAST ROOM PVCCINFAON_CPU0_CTRL
J 0
(-2325 1575);
DISPLAY 0.808511 (-2325 1575);
PAINT RED (-2325 1575);
DISPLAY INVISIBLE (-2325 1575);
FORCEPROP 2 LAST CDS_LIB mstr_symbols
J 0
(-2325 1475);
DISPLAY INVISIBLE (-2325 1475);
FORCEPROP 1 LAST PATH I550
J 0
(-2275 1500);
DISPLAY 0.872340 (-2275 1500);
PAINT AQUA (-2275 1500);
DISPLAY INVISIBLE (-2275 1500);
FORCEADD OFFPAGE..6
(-5425 900);
FORCEPROP 2 LAST $XR5 91 
J 0
(-6154 900);
DISPLAY 0.638298 (-6154 900);
PAINT MONO (-6154 900);
FORCEPROP 2 LAST $XR4 90 
J 0
(-6064 900);
DISPLAY 0.638298 (-6064 900);
PAINT MONO (-6064 900);
FORCEPROP 2 LAST $XR3 89 
J 0
(-5974 900);
DISPLAY 0.638298 (-5974 900);
PAINT MONO (-5974 900);
FORCEPROP 2 LAST $XR2 88 
J 0
(-5884 900);
DISPLAY 0.638298 (-5884 900);
PAINT MONO (-5884 900);
FORCEPROP 2 LAST $XR1 87 
J 0
(-5794 900);
DISPLAY 0.638298 (-5794 900);
PAINT MONO (-5794 900);
FORCEPROP 2 LAST $XR0 86 
J 0
(-5704 900);
DISPLAY 0.638298 (-5704 900);
PAINT MONO (-5704 900);
FORCEPROP 2 LAST CDS_LIB mstr_standard
J 0
(-5425 900);
DISPLAY INVISIBLE (-5425 900);
FORCEPROP 1 LAST OFFPAGE TRUE
J 0
(-5100 775);
DISPLAY 0.872340 (-5100 775);
PAINT GREEN (-5100 775);
DISPLAY INVISIBLE (-5100 775);
FORCEPROP 1 LAST COMMENT_BODY TRUE
J 0
(-5325 825);
DISPLAY 0.872340 (-5325 825);
PAINT GREEN (-5325 825);
DISPLAY INVISIBLE (-5325 825);
FORCEPROP 2 LAST PATH I551
J 0
(-5375 975);
DISPLAY 0.680851 (-5375 975);
DISPLAY INVISIBLE (-5375 975);
FORCEADD OFFPAGE..6
R 2
(-1900 900);
FORCEPROP 2 LAST $XR0 82 
J 0
(-1686 900);
DISPLAY 0.638298 (-1686 900);
PAINT MONO (-1686 900);
FORCEPROP 2 LAST CDS_LIB mstr_standard
J 2
(-1900 900);
DISPLAY INVISIBLE (-1900 900);
FORCEPROP 1 LAST OFFPAGE TRUE
J 2
(-2225 775);
DISPLAY 0.872340 (-2225 775);
PAINT GREEN (-2225 775);
DISPLAY INVISIBLE (-2225 775);
FORCEPROP 1 LAST COMMENT_BODY TRUE
J 2
(-2000 825);
DISPLAY 0.872340 (-2000 825);
PAINT GREEN (-2000 825);
DISPLAY INVISIBLE (-2000 825);
FORCEPROP 2 LAST PATH I552
J 2
(-1950 975);
DISPLAY 0.680851 (-1950 975);
DISPLAY INVISIBLE (-1950 975);
FORCEADD OFFPAGE..6
(-8875 2800);
FORCEPROP 2 LAST $XR5 159 
J 0
(-9244 2764);
DISPLAY 0.638298 (-9244 2764);
PAINT MONO (-9244 2764);
FORCEPROP 2 LAST $XR4 91 
J 0
(-9124 2764);
DISPLAY 0.638298 (-9124 2764);
PAINT MONO (-9124 2764);
FORCEPROP 2 LAST $XR3 90 
J 0
(-9394 2800);
DISPLAY 0.638298 (-9394 2800);
PAINT MONO (-9394 2800);
FORCEPROP 2 LAST $XR2 89 
J 0
(-9304 2800);
DISPLAY 0.638298 (-9304 2800);
PAINT MONO (-9304 2800);
FORCEPROP 2 LAST $XR1 88 
J 0
(-9214 2800);
DISPLAY 0.638298 (-9214 2800);
PAINT MONO (-9214 2800);
FORCEPROP 2 LAST $XR0 87 
J 0
(-9124 2800);
DISPLAY 0.638298 (-9124 2800);
PAINT MONO (-9124 2800);
FORCEPROP 2 LAST CDS_LIB mstr_standard
J 0
(-8875 2800);
DISPLAY 0.808511 (-8875 2800);
DISPLAY INVISIBLE (-8875 2800);
FORCEPROP 1 LAST OFFPAGE TRUE
J 0
(-8550 2675);
DISPLAY 0.872340 (-8550 2675);
PAINT GREEN (-8550 2675);
DISPLAY INVISIBLE (-8550 2675);
FORCEPROP 1 LAST COMMENT_BODY TRUE
J 0
(-8775 2725);
DISPLAY 0.872340 (-8775 2725);
PAINT GREEN (-8775 2725);
DISPLAY INVISIBLE (-8775 2725);
FORCEPROP 2 LAST PATH I553
J 0
(-9150 2850);
DISPLAY 0.680851 (-9150 2850);
DISPLAY INVISIBLE (-9150 2850);
FORCEADD Q_RES..1
(-8125 2875);
FORCEPROP 1 LAST LOCATION R1674
J 0
(-8300 2875);
DISPLAY 0.510638 (-8300 2875);
FORCEPROP 2 LAST SEC 1
J 0
(-8175 3075);
DISPLAY 0.680851 (-8175 3075);
PAINT MONO (-8175 3075);
DISPLAY INVISIBLE (-8175 3075);
FORCEPROP 1 LASTPIN (-8225 2875) $PN 1
J 0
(-8213 2887);
DISPLAY 0.787234 (-8213 2887);
PAINT MONO (-8213 2887);
FORCEPROP 1 LASTPIN (-8025 2875) $PN 2
J 0
(-8063 2887);
DISPLAY 0.787234 (-8063 2887);
PAINT MONO (-8063 2887);
FORCEPROP 1 LAST PACK_TYPE 0402LF
J 0
(-8075 2850);
DISPLAY 0.404255 (-8075 2850);
FORCEPROP 1 LAST VALUE 10
J 2
(-7950 2875);
DISPLAY 0.404255 (-7950 2875);
FORCEPROP 1 LAST MATERIAL CHIP
J 0
(-8250 2850);
DISPLAY 0.404255 (-8250 2850);
FORCEPROP 2 LAST SEC_TYPE 0402LF
J 0
(-8175 3075);
DISPLAY 0.680851 (-8175 3075);
DISPLAY INVISIBLE (-8175 3075);
FORCEPROP 1 LAST TOLERANCE 1%
J 0
(-8125 2775);
DISPLAY 0.978723 (-8125 2775);
DISPLAY INVISIBLE (-8125 2775);
FORCEPROP 1 LAST WATTAGE 1/16W
J 2
(-8150 2725);
DISPLAY 0.978723 (-8150 2725);
DISPLAY INVISIBLE (-8150 2725);
FORCEPROP 2 LAST CDS_LIB pure_quanta
J 0
(-8125 2875);
DISPLAY INVISIBLE (-8125 2875);
FORCEPROP 1 LAST PATH I554
J 0
(-8175 3025);
DISPLAY 0.978723 (-8175 3025);
PAINT WHITE (-8175 3025);
DISPLAY INVISIBLE (-8175 3025);
FORCEPROP 1 LAST PART_NUMBER CS01002FB07
J 0
(-8175 2975);
DISPLAY 0.978723 (-8175 2975);
DISPLAY INVISIBLE (-8175 2975);
FORCEADD DNS..2
(-8800 2425);
PAINT RED (-8800 2425);
FORCEPROP 2 LAST CDS_LIB mstr_misc
J 0
(-8800 2425);
DISPLAY INVISIBLE (-8800 2425);
FORCEPROP 1 LAST COMMENT_BODY TRUE
R 1
J 0
(-8725 2200);
DISPLAY 0.872340 (-8725 2200);
PAINT PEACH (-8725 2200);
DISPLAY INVISIBLE (-8725 2200);
FORCEADD DNS..2
(-2975 1475);
PAINT RED (-2975 1475);
FORCEPROP 2 LAST CDS_LIB mstr_misc
J 0
(-2975 1475);
DISPLAY INVISIBLE (-2975 1475);
FORCEPROP 1 LAST COMMENT_BODY TRUE
R 1
J 0
(-2900 1250);
DISPLAY 0.872340 (-2900 1250);
PAINT PEACH (-2900 1250);
DISPLAY INVISIBLE (-2900 1250);
FORCEADD DNS..2
(-8425 2400);
PAINT RED (-8425 2400);
FORCEPROP 2 LAST CDS_LIB mstr_misc
J 0
(-8425 2400);
DISPLAY INVISIBLE (-8425 2400);
FORCEPROP 1 LAST COMMENT_BODY TRUE
R 1
J 0
(-8350 2175);
DISPLAY 0.872340 (-8350 2175);
PAINT PEACH (-8350 2175);
DISPLAY INVISIBLE (-8350 2175);
FORCEADD DNS..2
(-4925 1325);
PAINT RED (-4925 1325);
FORCEPROP 2 LAST CDS_LIB mstr_misc
J 0
(-4925 1325);
DISPLAY INVISIBLE (-4925 1325);
FORCEPROP 1 LAST COMMENT_BODY TRUE
R 1
J 0
(-4850 1100);
DISPLAY 0.872340 (-4850 1100);
PAINT PEACH (-4850 1100);
DISPLAY INVISIBLE (-4850 1100);
FORCEADD QUANTA_TITLE_BLOCK_C..1
(-100 100);
FORCEPROP 0 LAST CDS_CON_LAST_MODIFIED Thu Sep 14 16:12:05 2023
J 0
(-1985 115);
DISPLAY INVISIBLE (-1985 115);
FORCEPROP 1 LAST CUSTOM_TXT_CDS <CON_LAST_MODIFIED>
J 0
(-1985 115);
DISPLAY 0.978723 (-1985 115);
FORCEPROP 2 LAST CUSTOM_TXT_CDS <XR_PAGE_TITLE>
J 0
(-7990 5350);
DISPLAY 0.638298 (-7990 5350);
PAINT PINK (-7990 5350);
DISPLAY INVISIBLE (-7990 5350);
FORCEPROP 1 LAST CUSTOM_TXT_CDS <NAME_2>
J 0
(-3275 150);
FORCEPROP 1 LAST CUSTOM_TXT_CDS <NAME_1>
J 0
(-3275 275);
FORCEPROP 1 LAST CUSTOM_TXT_CDS <Q_NUMBER>
J 0
(-1503 203);
DISPLAY 1.212766 (-1503 203);
FORCEPROP 1 LAST CUSTOM_TXT_CDS <Q_PROJ>
J 0
(-2482 202);
DISPLAY 1.212766 (-2482 202);
FORCEPROP 1 LAST CUSTOM_TXT_CDS <Q_REV>
J 0
(-284 203);
DISPLAY 1.212766 (-284 203);
FORCEPROP 1 LAST CUSTOM_TXT_CDS <CON_PAGE_NUM> OF <CON_TOTAL_PAGES>
J 0
(-546 118);
DISPLAY 0.978723 (-546 118);
FORCEPROP 1 LAST Q_TITLE DDR5 - CPU0 CHA
J 0
(-9425 150);
DISPLAY 2.446809 (-9425 150);
PAINT GREEN (-9425 150);
FORCEPROP 2 LAST PAGE_BORDER TRUE
J 0
(-7990 5350);
DISPLAY 0.638298 (-7990 5350);
PAINT PINK (-7990 5350);
DISPLAY INVISIBLE (-7990 5350);
FORCEPROP 1 LAST CDS_LMAN_SYM_OUTLINE -9475,6775,100,-125
J 0
(-100 100);
DISPLAY 0.468085 (-100 100);
PAINT GREEN (-100 100);
DISPLAY INVISIBLE (-100 100);
FORCEPROP 2 LAST CDS_LIB pure_quanta
J 0
(-100 100);
DISPLAY INVISIBLE (-100 100);
FORCEPROP 2 LAST CDS_XR_PAGE_TITLE CR-86 : @T6G_MB_LIB.T6G(SCH_1):PAGE86
J 0
(-7990 5350);
DISPLAY 0.638298 (-7990 5350);
PAINT PINK (-7990 5350);
DISPLAY INVISIBLE (-7990 5350);
FORCEPROP 1 LAST Q_DEPT BU9
J 1
(-3863 149);
DISPLAY 1.957447 (-3863 149);
PAINT GREEN (-3863 149);
DISPLAY INVISIBLE (-3863 149);
FORCEPROP 1 LAST COMMENT_BODY TRUE
J 0
(-88 87);
DISPLAY 0.978723 (-88 87);
PAINT GREEN (-88 87);
DISPLAY INVISIBLE (-88 87);
WIRE 17 -1 (-7800 3400)(-7800 3450);
WIRE 17 -1 (-7800 3350)(-7800 3400);
WIRE 17 -1 (-7800 3500)(-7800 3450);
WIRE 17 -1 (-7800 3500)(-7800 3550);
WIRE 17 -1 (-7800 3300)(-7800 3350);
WIRE 17 -1 (-7800 3250)(-7800 3300);
WIRE 17 -1 (-7800 3600)(-7800 3550);
WIRE 17 -1 (-7800 3600)(-7800 3625);
WIRE 17 -1 (-7800 3625)(-8300 3625);
FORCEPROP 2 LAST SIG_NAME M_A_CPU0_SB_CB<7:0>
J 0
(-8300 3635);
DISPLAY 0.489362 (-8300 3635);
WIRE 17 -1 (-7800 3700)(-7800 3750);
WIRE 17 -1 (-7800 3750)(-7800 3800);
WIRE 17 -1 (-7800 3800)(-7800 3850);
WIRE 17 -1 (-7800 3850)(-7800 3900);
WIRE 17 -1 (-7800 3950)(-7800 3900);
WIRE 17 -1 (-7800 3950)(-7800 4000);
WIRE 17 -1 (-7800 4050)(-7800 4000);
WIRE 17 -1 (-7800 4050)(-7800 4075);
WIRE 17 -1 (-7800 4075)(-8300 4075);
FORCEPROP 2 LAST SIG_NAME M_A_CPU0_SA_CB<7:0>
J 0
(-8300 4085);
DISPLAY 0.489362 (-8300 4085);
WIRE 17 -1 (-6000 3200)(-6000 3150);
WIRE 17 -1 (-6000 3250)(-6000 3200);
WIRE 17 -1 (-6000 3150)(-6000 3100);
WIRE 17 -1 (-6000 3100)(-6000 3050);
WIRE 17 -1 (-6000 3300)(-6000 3250);
WIRE 17 -1 (-6000 3350)(-6000 3300);
WIRE 17 -1 (-6000 3000)(-6000 3050);
WIRE 17 -1 (-6000 2950)(-6000 3000);
WIRE 17 -1 (-6000 3400)(-6000 3350);
WIRE 17 -1 (-6000 3450)(-6000 3400);
WIRE 17 -1 (-6000 2900)(-6000 2950);
WIRE 17 -1 (-6000 2850)(-6000 2900);
WIRE 17 -1 (-6000 3500)(-6000 3450);
WIRE 17 -1 (-6000 3550)(-6000 3500);
WIRE 17 -1 (-6000 2850)(-6000 2800);
WIRE 17 -1 (-6000 2800)(-6000 2750);
WIRE 17 -1 (-6000 3600)(-6000 3550);
WIRE 17 -1 (-6000 3650)(-6000 3600);
WIRE 17 -1 (-6000 2750)(-6000 2700);
WIRE 17 -1 (-6000 2700)(-6000 2650);
WIRE 17 -1 (-6000 3700)(-6000 3650);
WIRE 17 -1 (-6000 3750)(-6000 3700);
WIRE 17 -1 (-6000 2650)(-6000 2600);
WIRE 17 -1 (-6000 2600)(-6000 2550);
WIRE 17 -1 (-6000 3800)(-6000 3750);
WIRE 17 -1 (-6000 3825)(-6000 3800);
WIRE 17 -1 (-6000 2550)(-6000 2500);
WIRE 17 -1 (-6000 2500)(-6000 2450);
WIRE 17 -1 (-6000 3825)(-5550 3825);
FORCEPROP 2 LAST SIG_NAME M_A_CPU0_SB_DQ<31:0>
J 2
(-5550 3835);
DISPLAY 0.489362 (-5550 3835);
WIRE 17 -1 (-7800 4750)(-7800 4800);
WIRE 17 -1 (-7800 4800)(-7800 4850);
WIRE 17 -1 (-7800 4850)(-7800 4900);
WIRE 17 -1 (-7800 4900)(-7800 4950);
WIRE 17 -1 (-7800 4950)(-7800 5000);
WIRE 17 -1 (-7800 5000)(-7800 5050);
WIRE 17 -1 (-7800 5050)(-7800 5075);
WIRE 17 -1 (-7800 5075)(-8300 5075);
FORCEPROP 2 LAST SIG_NAME M_A_CPU0_SB_CA<6:0>
J 0
(-8300 5085);
DISPLAY 0.489362 (-8300 5085);
WIRE 17 -1 (-7800 5200)(-7800 5250);
WIRE 17 -1 (-7800 5150)(-7800 5200);
WIRE 17 -1 (-7800 5250)(-7800 5300);
WIRE 17 -1 (-7800 5300)(-7800 5350);
WIRE 17 -1 (-7800 5350)(-7800 5400);
WIRE 17 -1 (-7800 5400)(-7800 5450);
WIRE 17 -1 (-7800 5450)(-7800 5475);
WIRE 17 -1 (-7800 5475)(-8300 5475);
FORCEPROP 2 LAST SIG_NAME M_A_CPU0_SA_CA<6:0>
J 0
(-8300 5485);
DISPLAY 0.489362 (-8300 5485);
WIRE 17 -1 (-6000 5100)(-6000 5050);
WIRE 17 -1 (-6000 5150)(-6000 5100);
WIRE 17 -1 (-6000 5050)(-6000 5000);
WIRE 17 -1 (-6000 5000)(-6000 4950);
WIRE 17 -1 (-6000 5200)(-6000 5150);
WIRE 17 -1 (-6000 5250)(-6000 5200);
WIRE 17 -1 (-6000 4950)(-6000 4900);
WIRE 17 -1 (-6000 4900)(-6000 4850);
WIRE 17 -1 (-6000 5300)(-6000 5250);
WIRE 17 -1 (-6000 5350)(-6000 5300);
WIRE 17 -1 (-6000 4850)(-6000 4800);
WIRE 17 -1 (-6000 4800)(-6000 4750);
WIRE 17 -1 (-6000 5400)(-6000 5350);
WIRE 17 -1 (-6000 5450)(-6000 5400);
WIRE 17 -1 (-6000 4750)(-6000 4700);
WIRE 17 -1 (-6000 4650)(-6000 4700);
WIRE 17 -1 (-6000 5475)(-6000 5450);
WIRE 17 -1 (-6000 5475)(-5550 5475);
FORCEPROP 2 LAST SIG_NAME M_A_CPU0_SA_DQ<31:0>
J 2
(-5550 5485);
DISPLAY 0.489362 (-5550 5485);
WIRE 17 -1 (-6000 4600)(-6000 4650);
WIRE 17 -1 (-6000 4550)(-6000 4600);
WIRE 17 -1 (-6000 4500)(-6000 4550);
WIRE 17 -1 (-6000 4500)(-6000 4450);
WIRE 17 -1 (-6000 4450)(-6000 4400);
WIRE 17 -1 (-6000 4400)(-6000 4350);
WIRE 17 -1 (-6000 4350)(-6000 4300);
WIRE 17 -1 (-6000 4300)(-6000 4250);
WIRE 17 -1 (-6000 4250)(-6000 4200);
WIRE 17 -1 (-6000 4200)(-6000 4150);
WIRE 17 -1 (-6000 4150)(-6000 4100);
WIRE 17 -1 (-6000 4050)(-6000 4100);
WIRE 17 -1 (-6000 4000)(-6000 4050);
WIRE 17 -1 (-6000 3950)(-6000 4000);
WIRE 17 -1 (-6000 3900)(-6000 3950);
WIRE 17 -1 (-6000 2400)(-6000 2450);
WIRE 17 -1 (-6000 2350)(-6000 2400);
WIRE 17 -1 (-6000 2300)(-6000 2350);
WIRE 17 -1 (-6000 2250)(-6000 2300);
WIRE 17 -1 (-3550 3550)(-3550 3450);
WIRE 17 -1 (-3550 3650)(-3550 3550);
WIRE 17 -1 (-3550 3650)(-3550 3750);
WIRE 17 -1 (-3550 3750)(-3550 3850);
WIRE 17 -1 (-3550 3850)(-3550 3950);
WIRE 17 -1 (-3550 4050)(-3550 3950);
WIRE 17 -1 (-3550 4150)(-3550 4050);
WIRE 17 -1 (-3550 4250)(-3550 4150);
WIRE 17 -1 (-3550 4350)(-3550 4250);
WIRE 17 -1 (-3550 4375)(-3550 4350);
WIRE 17 -1 (-3550 4375)(-2850 4375);
FORCEPROP 2 LAST SIG_NAME M_A_CPU0_SB_DQS_DP<9:0>
J 2
(-2850 4385);
DISPLAY 0.489362 (-2850 4385);
WIRE 17 -1 (-3350 4650)(-3350 4550);
WIRE 17 -1 (-3350 4650)(-3350 4750);
WIRE 17 -1 (-3350 4550)(-3350 4450);
WIRE 17 -1 (-3350 4750)(-3350 4850);
WIRE 17 -1 (-3350 4850)(-3350 4950);
WIRE 17 -1 (-3350 5050)(-3350 4950);
WIRE 17 -1 (-3350 5150)(-3350 5050);
WIRE 17 -1 (-3350 5250)(-3350 5150);
WIRE 17 -1 (-3350 5350)(-3350 5250);
WIRE 17 -1 (-3350 5375)(-3350 5350);
FORCEPROP 2 LAST SIG_NAME M_A_CPU0_SA_DQS_DN<9:0>
J 0
(-3385 5385);
DISPLAY 0.489362 (-3385 5385);
WIRE 17 -1 (-3550 4700)(-3550 4600);
WIRE 17 -1 (-3550 4700)(-3550 4800);
WIRE 17 -1 (-3550 4600)(-3550 4500);
WIRE 17 -1 (-3550 4800)(-3550 4900);
WIRE 17 -1 (-3550 4900)(-3550 5000);
WIRE 17 -1 (-3550 5100)(-3550 5000);
WIRE 17 -1 (-3550 5200)(-3550 5100);
WIRE 17 -1 (-3550 5300)(-3550 5200);
WIRE 17 -1 (-3550 5400)(-3550 5300);
WIRE 17 -1 (-3550 5425)(-3550 5400);
WIRE 17 -1 (-3550 5425)(-2850 5425);
FORCEPROP 2 LAST SIG_NAME M_A_CPU0_SA_DQS_DP<9:0>
J 0
(-3385 5435);
DISPLAY 0.489362 (-3385 5435);
WIRE 17 -1 (-3350 3600)(-3350 3700);
WIRE 17 -1 (-3350 3600)(-3350 3500);
WIRE 17 -1 (-3350 3700)(-3350 3800);
WIRE 17 -1 (-3350 3800)(-3350 3900);
WIRE 17 -1 (-3350 3500)(-3350 3400);
WIRE 17 -1 (-3350 4000)(-3350 3900);
WIRE 17 -1 (-3350 4100)(-3350 4000);
WIRE 17 -1 (-3350 4200)(-3350 4100);
WIRE 17 -1 (-3350 4300)(-3350 4200);
WIRE 17 -1 (-3350 4325)(-3350 4300);
WIRE 17 -1 (-3350 4325)(-2850 4325);
FORCEPROP 2 LAST SIG_NAME M_A_CPU0_SB_DQS_DN<9:0>
J 2
(-2850 4335);
DISPLAY 0.489362 (-2850 4335);
WIRE 16 -1 (-6500 1150)(-6500 1225);
WIRE 16 -1 (-9000 3050)(-9000 3125);
WIRE 16 -1 (-8700 2500)(-8700 2525);
WIRE 16 -1 (-8450 2500)(-8450 2525);
WIRE 16 -1 (-8750 1475)(-8750 1625);
WIRE 17 -1 (-3350 5375)(-2850 5375);
WIRE 16 -1 (-7500 3075)(-8300 3075);
FORCEPROP 2 LAST SIG_NAME M_A_CPU0_ALERT_N
J 0
(-8285 3085);
DISPLAY 0.489362 (-8285 3085);
WIRE 16 -1 (-7875 2700)(-8350 2700);
WIRE 16 -1 (-8225 2875)(-8300 2875);
WIRE 16 -1 (-8300 2800)(-8300 2875);
WIRE 16 -1 (-8300 2800)(-8825 2800);
FORCEPROP 2 LAST SIG_NAME I3C_SPD_DDRAF_CPU0_SDA
J 0
(-8835 2810);
DISPLAY 0.489362 (-8835 2810);
WIRE 16 -1 (-7500 2925)(-9050 2925);
FORCEPROP 2 LAST SIG_NAME PD_CHA_CPU0_DIMM0_SAA
J 0
(-9050 2935);
DISPLAY 0.489362 (-9050 2935);
WIRE 16 -1 (-9000 3325)(-9000 3400);
WIRE 16 -1 (-9000 3400)(-8875 3400);
WIRE 16 -1 (-8875 3475)(-8875 3400);
WIRE 16 -1 (-8875 3400)(-8875 2975);
WIRE 16 -1 (-8875 2975)(-7500 2975);
WIRE 16 -1 (-7500 4125)(-8300 4125);
FORCEPROP 2 LAST SIG_NAME M_A_CPU0_CLK_DN<0>
J 0
(-8300 4135);
DISPLAY 0.489362 (-8300 4135);
WIRE 16 -1 (-7500 4275)(-8300 4275);
FORCEPROP 2 LAST SIG_NAME M_A_CPU0_SB_CS_N<0>
J 0
(-8300 4285);
DISPLAY 0.489362 (-8300 4285);
WIRE 16 -1 (-7500 3925)(-7700 3925);
WIRE 16 -1 (-7500 4175)(-8300 4175);
FORCEPROP 2 LAST SIG_NAME M_A_CPU0_CLK_DP<0>
J 0
(-8300 4185);
DISPLAY 0.489362 (-8300 4185);
WIRE 16 -1 (-650 5350)(-650 5300);
WIRE 16 -1 (-650 5350)(-850 5350);
WIRE 16 -1 (-650 5300)(-650 5250);
WIRE 16 -1 (-650 5300)(-850 5300);
WIRE 16 -1 (-650 5250)(-650 5200);
WIRE 16 -1 (-650 5250)(-850 5250);
WIRE 16 -1 (-650 5200)(-650 5150);
WIRE 16 -1 (-650 5200)(-850 5200);
WIRE 16 -1 (-650 5150)(-850 5150);
WIRE 16 -1 (-650 5150)(-650 5100);
WIRE 16 -1 (-650 5100)(-650 5050);
WIRE 16 -1 (-650 5100)(-850 5100);
WIRE 16 -1 (-650 5050)(-650 5000);
WIRE 16 -1 (-650 5050)(-850 5050);
WIRE 16 -1 (-650 5000)(-650 4950);
WIRE 16 -1 (-650 5000)(-850 5000);
WIRE 16 -1 (-650 4950)(-650 4900);
WIRE 16 -1 (-650 4950)(-850 4950);
WIRE 16 -1 (-650 4900)(-650 4850);
WIRE 16 -1 (-650 4900)(-850 4900);
WIRE 16 -1 (-650 4850)(-650 4800);
WIRE 16 -1 (-650 4850)(-850 4850);
WIRE 16 -1 (-650 4800)(-650 4750);
WIRE 16 -1 (-650 4800)(-850 4800);
WIRE 16 -1 (-650 4750)(-650 4700);
WIRE 16 -1 (-650 4750)(-850 4750);
WIRE 16 -1 (-650 4700)(-650 4650);
WIRE 16 -1 (-650 4700)(-850 4700);
WIRE 16 -1 (-650 4650)(-850 4650);
WIRE 16 -1 (-650 4650)(-650 4600);
WIRE 16 -1 (-650 4600)(-650 4550);
WIRE 16 -1 (-650 4600)(-850 4600);
WIRE 16 -1 (-650 4550)(-650 4500);
WIRE 16 -1 (-650 4550)(-850 4550);
WIRE 16 -1 (-650 4500)(-650 4450);
WIRE 16 -1 (-650 4500)(-850 4500);
WIRE 16 -1 (-650 4450)(-650 4400);
WIRE 16 -1 (-650 4450)(-850 4450);
WIRE 16 -1 (-650 4400)(-650 4350);
WIRE 16 -1 (-650 4400)(-850 4400);
WIRE 16 -1 (-650 4350)(-650 4300);
WIRE 16 -1 (-650 4350)(-850 4350);
WIRE 16 -1 (-650 4300)(-650 4250);
WIRE 16 -1 (-650 4300)(-850 4300);
WIRE 16 -1 (-650 4250)(-650 4200);
WIRE 16 -1 (-650 4250)(-850 4250);
WIRE 16 -1 (-650 4200)(-650 4150);
WIRE 16 -1 (-650 4200)(-850 4200);
WIRE 16 -1 (-650 4150)(-650 4100);
WIRE 16 -1 (-650 4150)(-850 4150);
WIRE 16 -1 (-650 4100)(-850 4100);
WIRE 16 -1 (-650 4100)(-650 4050);
WIRE 16 -1 (-650 4050)(-650 4000);
WIRE 16 -1 (-650 4050)(-850 4050);
WIRE 16 -1 (-650 4000)(-650 3950);
WIRE 16 -1 (-650 4000)(-850 4000);
WIRE 16 -1 (-650 3950)(-650 3900);
WIRE 16 -1 (-650 3950)(-850 3950);
WIRE 16 -1 (-650 3900)(-650 3850);
WIRE 16 -1 (-650 3900)(-850 3900);
WIRE 16 -1 (-650 3850)(-650 3800);
WIRE 16 -1 (-650 3850)(-850 3850);
WIRE 16 -1 (-650 3800)(-650 3750);
WIRE 16 -1 (-650 3800)(-850 3800);
WIRE 16 -1 (-650 3750)(-650 3700);
WIRE 16 -1 (-650 3750)(-850 3750);
WIRE 16 -1 (-650 3700)(-650 3650);
WIRE 16 -1 (-650 3700)(-850 3700);
WIRE 16 -1 (-650 3650)(-650 3600);
WIRE 16 -1 (-650 3650)(-850 3650);
WIRE 16 -1 (-650 3600)(-850 3600);
WIRE 16 -1 (-650 3600)(-650 3550);
WIRE 16 -1 (-650 3550)(-650 3500);
WIRE 16 -1 (-650 3550)(-850 3550);
WIRE 16 -1 (-650 3500)(-650 3450);
WIRE 16 -1 (-650 3500)(-850 3500);
WIRE 16 -1 (-650 3450)(-650 3400);
WIRE 16 -1 (-650 3450)(-850 3450);
WIRE 16 -1 (-650 3400)(-650 3350);
WIRE 16 -1 (-650 3400)(-850 3400);
WIRE 16 -1 (-650 3350)(-650 3300);
WIRE 16 -1 (-650 3350)(-850 3350);
WIRE 16 -1 (-650 3300)(-650 3250);
WIRE 16 -1 (-650 3300)(-850 3300);
WIRE 16 -1 (-650 3250)(-650 3200);
WIRE 16 -1 (-650 3250)(-850 3250);
WIRE 16 -1 (-650 3200)(-650 3150);
WIRE 16 -1 (-650 3200)(-850 3200);
WIRE 16 -1 (-650 3150)(-650 3100);
WIRE 16 -1 (-650 3150)(-850 3150);
WIRE 16 -1 (-650 3100)(-850 3100);
WIRE 16 -1 (-650 3100)(-650 3050);
WIRE 16 -1 (-650 3050)(-650 3000);
WIRE 16 -1 (-650 3050)(-850 3050);
WIRE 16 -1 (-650 3000)(-650 2950);
WIRE 16 -1 (-650 3000)(-850 3000);
WIRE 16 -1 (-650 2950)(-650 2900);
WIRE 16 -1 (-650 2950)(-850 2950);
WIRE 16 -1 (-650 2900)(-650 2850);
WIRE 16 -1 (-650 2900)(-850 2900);
WIRE 16 -1 (-650 2850)(-650 2800);
WIRE 16 -1 (-650 2850)(-850 2850);
WIRE 16 -1 (-650 2800)(-650 2750);
WIRE 16 -1 (-650 2800)(-850 2800);
WIRE 16 -1 (-650 2750)(-650 2700);
WIRE 16 -1 (-650 2750)(-850 2750);
WIRE 16 -1 (-650 2700)(-650 2650);
WIRE 16 -1 (-650 2700)(-850 2700);
WIRE 16 -1 (-650 2650)(-650 2600);
WIRE 16 -1 (-650 2650)(-850 2650);
WIRE 16 -1 (-650 2600)(-850 2600);
WIRE 16 -1 (-650 2600)(-650 2550);
WIRE 16 -1 (-650 2550)(-650 2500);
WIRE 16 -1 (-650 2550)(-850 2550);
WIRE 16 -1 (-650 2500)(-650 2450);
WIRE 16 -1 (-650 2500)(-850 2500);
WIRE 16 -1 (-650 2450)(-650 2400);
WIRE 16 -1 (-650 2450)(-850 2450);
WIRE 16 -1 (-650 2400)(-650 2350);
WIRE 16 -1 (-650 2400)(-850 2400);
WIRE 16 -1 (-650 2350)(-650 2300);
WIRE 16 -1 (-650 2350)(-850 2350);
WIRE 16 -1 (-650 2300)(-650 2250);
WIRE 16 -1 (-650 2300)(-850 2300);
WIRE 16 -1 (-650 2250)(-650 2200);
WIRE 16 -1 (-650 2250)(-850 2250);
WIRE 16 -1 (-650 2200)(-650 2100);
WIRE 16 -1 (-650 2200)(-850 2200);
WIRE 16 -1 (-650 2100)(-650 2050);
WIRE 16 -1 (-650 2100)(-850 2100);
WIRE 16 -1 (-650 2050)(-850 2050);
WIRE 16 -1 (-650 2050)(-650 2000);
WIRE 16 -1 (-650 2000)(-650 1800);
WIRE 16 -1 (-650 2000)(-850 2000);
WIRE 16 -1 (-2050 5200)(-2250 5200);
WIRE 16 -1 (-2250 5200)(-2250 5150);
WIRE 16 -1 (-2050 5150)(-2250 5150);
WIRE 16 -1 (-2250 5150)(-2250 5100);
WIRE 16 -1 (-2050 5100)(-2250 5100);
WIRE 16 -1 (-2250 5100)(-2250 5050);
WIRE 16 -1 (-2050 5050)(-2250 5050);
WIRE 16 -1 (-2250 5050)(-2250 5000);
WIRE 16 -1 (-2050 5000)(-2250 5000);
WIRE 16 -1 (-2250 5000)(-2250 4950);
WIRE 16 -1 (-2050 4950)(-2250 4950);
WIRE 16 -1 (-2250 4950)(-2250 4900);
WIRE 16 -1 (-2050 4900)(-2250 4900);
WIRE 16 -1 (-2250 4900)(-2250 4850);
WIRE 16 -1 (-2050 4850)(-2250 4850);
WIRE 16 -1 (-2250 4850)(-2250 4800);
WIRE 16 -1 (-2050 4800)(-2250 4800);
WIRE 16 -1 (-2250 4800)(-2250 4750);
WIRE 16 -1 (-2050 4750)(-2250 4750);
WIRE 16 -1 (-2250 4750)(-2250 4700);
WIRE 16 -1 (-2050 4700)(-2250 4700);
WIRE 16 -1 (-2250 4700)(-2250 4650);
WIRE 16 -1 (-2050 4650)(-2250 4650);
WIRE 16 -1 (-2250 4650)(-2250 4600);
WIRE 16 -1 (-2050 4600)(-2250 4600);
WIRE 16 -1 (-2250 4600)(-2250 4550);
WIRE 16 -1 (-2050 4550)(-2250 4550);
WIRE 16 -1 (-2250 4550)(-2250 4500);
WIRE 16 -1 (-2050 4500)(-2250 4500);
WIRE 16 -1 (-2250 4500)(-2250 4450);
WIRE 16 -1 (-2050 4450)(-2250 4450);
WIRE 16 -1 (-2250 4450)(-2250 4400);
WIRE 16 -1 (-2050 4400)(-2250 4400);
WIRE 16 -1 (-2250 4400)(-2250 4350);
WIRE 16 -1 (-2050 4350)(-2250 4350);
WIRE 16 -1 (-2250 4350)(-2250 4300);
WIRE 16 -1 (-2050 4300)(-2250 4300);
WIRE 16 -1 (-2250 4300)(-2250 4250);
WIRE 16 -1 (-2050 4250)(-2250 4250);
WIRE 16 -1 (-2250 4250)(-2250 4200);
WIRE 16 -1 (-2050 4200)(-2250 4200);
WIRE 16 -1 (-2250 4200)(-2250 4150);
WIRE 16 -1 (-2050 4150)(-2250 4150);
WIRE 16 -1 (-2250 4150)(-2250 4100);
WIRE 16 -1 (-2050 4100)(-2250 4100);
WIRE 16 -1 (-2250 4100)(-2250 4050);
WIRE 16 -1 (-2050 4050)(-2250 4050);
WIRE 16 -1 (-2250 4050)(-2250 4000);
WIRE 16 -1 (-2050 4000)(-2250 4000);
WIRE 16 -1 (-2250 4000)(-2250 3950);
WIRE 16 -1 (-2050 3950)(-2250 3950);
WIRE 16 -1 (-2250 3950)(-2250 3900);
WIRE 16 -1 (-2050 3900)(-2250 3900);
WIRE 16 -1 (-2250 3900)(-2250 3850);
WIRE 16 -1 (-2050 3850)(-2250 3850);
WIRE 16 -1 (-2250 3850)(-2250 3800);
WIRE 16 -1 (-2050 3800)(-2250 3800);
WIRE 16 -1 (-2250 3800)(-2250 3750);
WIRE 16 -1 (-2050 3750)(-2250 3750);
WIRE 16 -1 (-2250 3750)(-2250 3700);
WIRE 16 -1 (-2050 3700)(-2250 3700);
WIRE 16 -1 (-2250 3700)(-2250 3650);
WIRE 16 -1 (-2050 3650)(-2250 3650);
WIRE 16 -1 (-2250 3650)(-2250 3600);
WIRE 16 -1 (-2050 3600)(-2250 3600);
WIRE 16 -1 (-2250 3600)(-2250 3550);
WIRE 16 -1 (-2050 3550)(-2250 3550);
WIRE 16 -1 (-2250 3550)(-2250 3500);
WIRE 16 -1 (-2050 3500)(-2250 3500);
WIRE 16 -1 (-2250 3500)(-2250 3450);
WIRE 16 -1 (-2050 3450)(-2250 3450);
WIRE 16 -1 (-2250 3450)(-2250 3400);
WIRE 16 -1 (-2050 3400)(-2250 3400);
WIRE 16 -1 (-2250 3400)(-2250 3350);
WIRE 16 -1 (-2050 3350)(-2250 3350);
WIRE 16 -1 (-2250 3350)(-2250 3300);
WIRE 16 -1 (-2050 3300)(-2250 3300);
WIRE 16 -1 (-2250 3300)(-2250 3250);
WIRE 16 -1 (-2050 3250)(-2250 3250);
WIRE 16 -1 (-2250 3250)(-2250 3200);
WIRE 16 -1 (-2050 3200)(-2250 3200);
WIRE 16 -1 (-2250 3200)(-2250 3150);
WIRE 16 -1 (-2050 3150)(-2250 3150);
WIRE 16 -1 (-2250 3150)(-2250 3100);
WIRE 16 -1 (-2050 3100)(-2250 3100);
WIRE 16 -1 (-2250 3100)(-2250 3050);
WIRE 16 -1 (-2050 3050)(-2250 3050);
WIRE 16 -1 (-2250 3050)(-2250 3000);
WIRE 16 -1 (-2050 3000)(-2250 3000);
WIRE 16 -1 (-2250 3000)(-2250 2950);
WIRE 16 -1 (-2050 2950)(-2250 2950);
WIRE 16 -1 (-2250 2950)(-2250 2900);
WIRE 16 -1 (-2050 2900)(-2250 2900);
WIRE 16 -1 (-2250 2900)(-2250 2850);
WIRE 16 -1 (-2050 2850)(-2250 2850);
WIRE 16 -1 (-2250 2850)(-2250 2800);
WIRE 16 -1 (-2050 2800)(-2250 2800);
WIRE 16 -1 (-2250 2800)(-2250 2750);
WIRE 16 -1 (-2050 2750)(-2250 2750);
WIRE 16 -1 (-2250 2750)(-2250 2700);
WIRE 16 -1 (-2050 2700)(-2250 2700);
WIRE 16 -1 (-2250 2700)(-2250 2650);
WIRE 16 -1 (-2050 2650)(-2250 2650);
WIRE 16 -1 (-2250 2650)(-2250 2600);
WIRE 16 -1 (-2050 2600)(-2250 2600);
WIRE 16 -1 (-2250 2600)(-2250 2550);
WIRE 16 -1 (-2050 2550)(-2250 2550);
WIRE 16 -1 (-2250 2550)(-2250 2500);
WIRE 16 -1 (-2050 2500)(-2250 2500);
WIRE 16 -1 (-2250 2500)(-2250 2450);
WIRE 16 -1 (-2050 2450)(-2250 2450);
WIRE 16 -1 (-2250 2450)(-2250 2400);
WIRE 16 -1 (-2050 2400)(-2250 2400);
WIRE 16 -1 (-2250 2400)(-2250 2350);
WIRE 16 -1 (-2050 2350)(-2250 2350);
WIRE 16 -1 (-2250 2350)(-2250 2300);
WIRE 16 -1 (-2050 2300)(-2250 2300);
WIRE 16 -1 (-2250 2300)(-2250 2250);
WIRE 16 -1 (-2050 2250)(-2250 2250);
WIRE 16 -1 (-2250 2250)(-2250 2200);
WIRE 16 -1 (-2050 2200)(-2250 2200);
WIRE 16 -1 (-2250 2200)(-2250 2150);
WIRE 16 -1 (-2050 2150)(-2250 2150);
WIRE 16 -1 (-2250 2150)(-2250 2100);
WIRE 16 -1 (-2050 2100)(-2250 2100);
WIRE 16 -1 (-2250 2100)(-2250 2000);
WIRE 16 -1 (-2375 5825)(-2375 5950);
WIRE 16 -1 (-2375 5825)(-2950 5825);
WIRE 16 -1 (-2950 5825)(-2950 5950);
WIRE 16 -1 (-2950 5825)(-2950 5750);
WIRE 16 -1 (-2050 5250)(-2250 5250);
WIRE 16 -1 (-2250 5250)(-2250 5300);
WIRE 16 -1 (-2050 5300)(-2250 5300);
WIRE 16 -1 (-2250 5300)(-2250 5350);
WIRE 16 -1 (-2250 6250)(-2250 5350);
WIRE 16 -1 (-2050 5350)(-2250 5350);
WIRE 16 -1 (-2375 6250)(-2250 6250);
WIRE 16 -1 (-2375 6250)(-2375 6150);
WIRE 16 -1 (-2375 6250)(-2950 6250);
WIRE 16 -1 (-2950 6150)(-2950 6250);
WIRE 16 -1 (-2950 6250)(-2950 6325);
WIRE 16 -1 (-5550 1375)(-5050 1375);
WIRE 16 -1 (-5550 1525)(-5550 1375);
WIRE 16 -1 (-2325 1425)(-2325 1350);
WIRE 16 -1 (-2325 1350)(-2875 1350);
WIRE 16 -1 (-7500 2875)(-8025 2875);
FORCEPROP 2 LAST SIG_NAME I3C_SPD_DDRA_CPU0_SDA
J 0
(-7910 2885);
DISPLAY 0.361702 (-7910 2885);
FORCEPROP 2 LASTPROP $XRERR UNIQUE?
J 0
(-8150 2885);
DISPLAY 0.638298 (-8150 2885);
PAINT MONO (-8150 2885);
DISPLAY INVISIBLE (-8150 2885);
WIRE 16 -1 (-7500 2825)(-7600 2825);
FORCEPROP 2 LAST SIG_NAME I3C_SPD_DDRA_CPU0_SCL
J 0
(-7960 2775);
DISPLAY 0.361702 (-7960 2775);
FORCEPROP 2 LASTPROP $XRERR UNIQUE?
J 0
(-8200 2775);
DISPLAY 0.638298 (-8200 2775);
PAINT MONO (-8200 2775);
DISPLAY INVISIBLE (-8200 2775);
WIRE 16 -1 (-7600 2825)(-7600 2700);
WIRE 16 -1 (-7600 2700)(-7675 2700);
WIRE 16 -1 (-8450 2300)(-8450 2250);
WIRE 16 -1 (-8250 2250)(-8450 2250);
WIRE 16 -1 (-8450 2250)(-8475 2250);
WIRE 16 -1 (-8250 2250)(-8250 2575);
WIRE 16 -1 (-8250 2575)(-7500 2575);
FORCEPROP 2 LAST SIG_NAME PWRGD_CHA_CPU0_DIMM0
J 0
(-8160 2585);
DISPLAY 0.489362 (-8160 2585);
FORCEPROP 2 LASTPROP $XRERR UNIQUE?
J 0
(-8400 2585);
DISPLAY 0.638298 (-8400 2585);
PAINT MONO (-8400 2585);
DISPLAY INVISIBLE (-8400 2585);
WIRE 16 -1 (-7500 3125)(-8300 3125);
FORCEPROP 2 LAST SIG_NAME M_A_CPU0_RESET_N
J 0
(-8285 3135);
DISPLAY 0.489362 (-8285 3135);
WIRE 16 -1 (-7500 3725)(-7700 3725);
WIRE 16 -1 (-7500 3775)(-7700 3775);
WIRE 16 -1 (-6100 4325)(-6300 4325);
WIRE 16 -1 (-6100 4375)(-6300 4375);
WIRE 16 -1 (-6300 4425)(-6100 4425);
WIRE 16 -1 (-6100 4525)(-6300 4525);
WIRE 16 -1 (-7500 1975)(-8300 1975);
FORCEPROP 2 LAST SIG_NAME M_A_CPU0_SB_RSP<0>
J 0
(-8300 1985);
DISPLAY 0.489362 (-8300 1985);
WIRE 16 -1 (-6100 2425)(-6300 2425);
WIRE 16 -1 (-6300 2375)(-6100 2375);
WIRE 16 -1 (-6100 2225)(-6300 2225);
WIRE 16 -1 (-3450 3475)(-3850 3475);
WIRE 16 -1 (-3850 3375)(-3450 3375);
WIRE 16 -1 (-7500 3525)(-7700 3525);
WIRE 16 -1 (-3650 4225)(-3850 4225);
WIRE 16 -1 (-3450 4275)(-3850 4275);
WIRE 16 -1 (-3850 4425)(-3450 4425);
WIRE 16 -1 (-3650 4475)(-3850 4475);
WIRE 16 -1 (-6100 3875)(-6300 3875);
WIRE 16 -1 (-6100 3725)(-6300 3725);
WIRE 16 -1 (-6100 3475)(-6300 3475);
WIRE 16 -1 (-6300 4025)(-6100 4025);
WIRE 16 -1 (-6100 2325)(-6300 2325);
WIRE 16 -1 (-6100 2875)(-6300 2875);
WIRE 16 -1 (-7500 4825)(-7700 4825);
WIRE 16 -1 (-7500 3325)(-7700 3325);
WIRE 16 -1 (-7500 5275)(-7700 5275);
WIRE 16 -1 (-6100 4725)(-6300 4725);
WIRE 16 -1 (-7500 5125)(-7700 5125);
WIRE 16 -1 (-7500 3275)(-7700 3275);
WIRE 16 -1 (-7500 4575)(-8300 4575);
FORCEPROP 2 LAST SIG_NAME M_A_CPU0_SB_PAR
J 0
(-8300 4585);
DISPLAY 0.489362 (-8300 4585);
WIRE 16 -1 (-7500 3825)(-7700 3825);
WIRE 16 -1 (-7500 3875)(-7700 3875);
WIRE 16 -1 (-3850 4325)(-3650 4325);
WIRE 16 -1 (-3450 5025)(-3850 5025);
WIRE 16 -1 (-3650 5075)(-3850 5075);
WIRE 16 -1 (-3450 5125)(-3850 5125);
WIRE 16 -1 (-6100 4575)(-6300 4575);
WIRE 16 -1 (-6300 4625)(-6100 4625);
WIRE 16 -1 (-6100 4875)(-6300 4875);
WIRE 16 -1 (-6100 5075)(-6300 5075);
WIRE 16 -1 (-6100 5125)(-6300 5125);
WIRE 16 -1 (-6100 5175)(-6300 5175);
WIRE 16 -1 (-6300 5225)(-6100 5225);
WIRE 16 -1 (-6100 5275)(-6300 5275);
WIRE 16 -1 (-6100 5325)(-6300 5325);
WIRE 16 -1 (-3450 4175)(-3850 4175);
WIRE 16 -1 (-3650 4125)(-3850 4125);
WIRE 16 -1 (-3450 4075)(-3850 4075);
WIRE 16 -1 (-3650 4025)(-3850 4025);
WIRE 16 -1 (-3450 3975)(-3850 3975);
WIRE 16 -1 (-3450 3875)(-3850 3875);
WIRE 16 -1 (-3650 3825)(-3850 3825);
WIRE 16 -1 (-3450 3775)(-3850 3775);
WIRE 16 -1 (-6100 4675)(-6300 4675);
WIRE 16 -1 (-7500 4475)(-8300 4475);
FORCEPROP 2 LAST SIG_NAME M_A_CPU0_SA_CS_N<1>
J 0
(-8300 4485);
DISPLAY 0.489362 (-8300 4485);
WIRE 16 -1 (-7500 5425)(-7700 5425);
WIRE 16 -1 (-6300 5425)(-6100 5425);
WIRE 16 -1 (-7500 4975)(-7700 4975);
WIRE 16 -1 (-3850 5375)(-3650 5375);
WIRE 16 -1 (-3450 5325)(-3850 5325);
WIRE 16 -1 (-6100 5375)(-6300 5375);
WIRE 16 -1 (-3650 5275)(-3850 5275);
WIRE 16 -1 (-3450 5225)(-3850 5225);
WIRE 16 -1 (-3650 5175)(-3850 5175);
WIRE 16 -1 (-3850 3925)(-3650 3925);
WIRE 16 -1 (-3850 4975)(-3650 4975);
WIRE 16 -1 (-3450 4925)(-3850 4925);
WIRE 16 -1 (-3650 4875)(-3850 4875);
WIRE 16 -1 (-3450 4825)(-3850 4825);
WIRE 16 -1 (-3650 3725)(-3850 3725);
WIRE 16 -1 (-3450 3675)(-3850 3675);
WIRE 16 -1 (-3650 4775)(-3850 4775);
WIRE 16 -1 (-3450 4725)(-3850 4725);
WIRE 16 -1 (-3650 3625)(-3850 3625);
WIRE 16 -1 (-3450 3575)(-3850 3575);
WIRE 16 -1 (-3650 4675)(-3850 4675);
WIRE 16 -1 (-3450 4625)(-3850 4625);
WIRE 16 -1 (-3850 3525)(-3650 3525);
WIRE 16 -1 (-3850 4575)(-3650 4575);
WIRE 16 -1 (-3450 4525)(-3850 4525);
WIRE 16 -1 (-3650 3425)(-3850 3425);
WIRE 16 -1 (-7500 5375)(-7700 5375);
WIRE 16 -1 (-7500 4775)(-7700 4775);
WIRE 16 -1 (-7500 4925)(-7700 4925);
WIRE 16 -1 (-7500 5325)(-7700 5325);
WIRE 16 -1 (-7500 4625)(-8300 4625);
FORCEPROP 2 LAST SIG_NAME M_A_CPU0_SA_PAR
J 0
(-8300 4635);
DISPLAY 0.489362 (-8300 4635);
WIRE 16 -1 (-6100 2275)(-6300 2275);
WIRE 16 -1 (-6100 2475)(-6300 2475);
WIRE 16 -1 (-6100 2525)(-6300 2525);
WIRE 16 -1 (-6300 2575)(-6100 2575);
WIRE 16 -1 (-6100 2625)(-6300 2625);
WIRE 16 -1 (-6100 2675)(-6300 2675);
WIRE 16 -1 (-6100 2725)(-6300 2725);
WIRE 16 -1 (-6300 2775)(-6100 2775);
WIRE 16 -1 (-6100 2825)(-6300 2825);
WIRE 16 -1 (-6100 2925)(-6300 2925);
WIRE 16 -1 (-6300 2975)(-6100 2975);
WIRE 16 -1 (-6100 3025)(-6300 3025);
WIRE 16 -1 (-6100 3075)(-6300 3075);
WIRE 16 -1 (-6100 3225)(-6300 3225);
WIRE 16 -1 (-6100 3275)(-6300 3275);
WIRE 16 -1 (-6100 3325)(-6300 3325);
WIRE 16 -1 (-6300 3375)(-6100 3375);
WIRE 16 -1 (-6100 3425)(-6300 3425);
WIRE 16 -1 (-6100 3525)(-6300 3525);
WIRE 16 -1 (-6300 3575)(-6100 3575);
WIRE 16 -1 (-6100 3625)(-6300 3625);
WIRE 16 -1 (-6100 3675)(-6300 3675);
WIRE 16 -1 (-6300 3775)(-6100 3775);
WIRE 16 -1 (-6100 3925)(-6300 3925);
WIRE 16 -1 (-6100 3975)(-6300 3975);
WIRE 16 -1 (-6100 4075)(-6300 4075);
WIRE 16 -1 (-6100 4125)(-6300 4125);
WIRE 16 -1 (-6100 4175)(-6300 4175);
WIRE 16 -1 (-6300 4225)(-6100 4225);
WIRE 16 -1 (-6100 4275)(-6300 4275);
WIRE 16 -1 (-6100 4475)(-6300 4475);
WIRE 16 -1 (-6100 4775)(-6300 4775);
WIRE 16 -1 (-6300 4825)(-6100 4825);
WIRE 16 -1 (-6100 4925)(-6300 4925);
WIRE 16 -1 (-6100 4975)(-6300 4975);
WIRE 16 -1 (-6300 5025)(-6100 5025);
WIRE 16 -1 (-7500 3225)(-7700 3225);
WIRE 16 -1 (-7500 3425)(-7700 3425);
WIRE 16 -1 (-7500 3475)(-7700 3475);
WIRE 16 -1 (-7500 3975)(-7700 3975);
WIRE 16 -1 (-7500 5025)(-7700 5025);
WIRE 16 -1 (-7500 4875)(-7700 4875);
WIRE 16 -1 (-7500 5225)(-7700 5225);
WIRE 16 -1 (-7500 5175)(-7700 5175);
WIRE 16 -1 (-7500 4725)(-7700 4725);
WIRE 16 -1 (-7500 4025)(-7700 4025);
WIRE 16 -1 (-6300 3175)(-6100 3175);
WIRE 16 -1 (-6100 3125)(-6300 3125);
WIRE 16 -1 (-6500 1500)(-6500 1425);
WIRE 16 -1 (-6500 1500)(-7225 1500);
FORCEPROP 2 LAST SIG_NAME PD_CHA_CPU0_DIMM0_SAA
J 0
(-7210 1510);
DISPLAY 0.489362 (-7210 1510);
WIRE 16 -1 (-3125 1350)(-3300 1350);
WIRE 16 -1 (-3300 1350)(-3300 900);
WIRE 16 -1 (-3300 900)(-3200 900);
WIRE 16 -1 (-4275 900)(-3300 900);
FORCEPROP 2 LAST SIG_NAME PWRGD_CHAF_CPU0_R1
J 0
(-4060 910);
DISPLAY 0.680851 (-4060 910);
FORCEPROP 2 LASTPROP $XRERR UNIQUE?
J 0
(-4300 910);
DISPLAY 0.638298 (-4300 910);
PAINT MONO (-4300 910);
DISPLAY INVISIBLE (-4300 910);
WIRE 16 -1 (-4275 1375)(-4275 900);
WIRE 16 -1 (-4425 900)(-4275 900);
WIRE 16 -1 (-4850 1375)(-4275 1375);
WIRE 16 -1 (-3000 900)(-1950 900);
FORCEPROP 2 LAST SIG_NAME PWRGD_CHAF_CPU0_R2
J 0
(-2560 910);
DISPLAY 0.680851 (-2560 910);
WIRE 16 -1 (-8700 2300)(-8700 2250);
WIRE 16 -1 (-8675 2250)(-8700 2250);
WIRE 16 -1 (-8700 2250)(-9025 2250);
FORCEPROP 2 LAST SIG_NAME PWRGD_CHAF_CPU0
J 0
(-9060 2260);
DISPLAY 0.489362 (-9060 2260);
WIRE 16 -1 (-8750 975)(-7775 975);
FORCEPROP 2 LAST SIG_NAME PWRGD_CHAF_CPU0
J 0
(-8535 985);
DISPLAY 0.680851 (-8535 985);
WIRE 16 -1 (-8750 1275)(-8750 975);
WIRE 16 -1 (-5375 900)(-4625 900);
FORCEPROP 2 LAST SIG_NAME PWRGD_CHAF_CPU0
J 0
(-5260 910);
DISPLAY 0.680851 (-5260 910);
WIRE 16 -1 (-7500 2025)(-8300 2025);
FORCEPROP 2 LAST SIG_NAME M_A_CPU0_SA_RSP<0>
J 0
(-8300 2035);
DISPLAY 0.489362 (-8300 2035);
WIRE 16 -1 (-7500 3675)(-7700 3675);
WIRE 16 -1 (-7500 3575)(-7700 3575);
WIRE 16 -1 (-7500 4425)(-8300 4425);
FORCEPROP 2 LAST SIG_NAME M_A_CPU0_SA_CS_N<0>
J 0
(-8300 4435);
DISPLAY 0.489362 (-8300 4435);
WIRE 16 -1 (-7500 4325)(-8300 4325);
FORCEPROP 2 LAST SIG_NAME M_A_CPU0_SB_CS_N<1>
J 0
(-8300 4335);
DISPLAY 0.489362 (-8300 4335);
WIRE 16 -1 (-7500 3375)(-7700 3375);
DOT 1 (-4275 900);
DOT 1 (-3300 900);
DOT 1 (-2250 3800);
DOT 1 (-2250 4750);
DOT 1 (-650 4700);
DOT 1 (-2250 4950);
DOT 1 (-2250 5050);
DOT 1 (-2250 4850);
DOT 1 (-8450 2250);
DOT 1 (-2250 4400);
DOT 1 (-2250 4350);
DOT 1 (-650 4100);
DOT 1 (-650 4200);
DOT 1 (-650 4550);
DOT 1 (-2250 4450);
DOT 1 (-2250 4500);
DOT 1 (-2250 4550);
DOT 1 (-2250 4600);
DOT 1 (-2250 4650);
DOT 1 (-2250 4700);
DOT 1 (-2250 4300);
DOT 1 (-2250 2150);
DOT 1 (-2250 2100);
DOT 1 (-2250 2200);
DOT 1 (-2250 2250);
DOT 1 (-2250 2300);
DOT 1 (-2250 2400);
DOT 1 (-2250 2350);
DOT 1 (-2250 2450);
DOT 1 (-2250 2500);
DOT 1 (-2250 2550);
DOT 1 (-2250 2650);
DOT 1 (-2250 2600);
DOT 1 (-2250 2700);
DOT 1 (-2250 2750);
DOT 1 (-2250 2800);
DOT 1 (-2250 2900);
DOT 1 (-2250 2950);
DOT 1 (-2250 3000);
DOT 1 (-2250 3050);
DOT 1 (-2250 3150);
DOT 1 (-2250 3200);
DOT 1 (-2250 3100);
DOT 1 (-2250 3250);
DOT 1 (-2250 3300);
DOT 1 (-2250 3350);
DOT 1 (-2250 3400);
DOT 1 (-2250 3450);
DOT 1 (-2250 3500);
DOT 1 (-2250 3550);
DOT 1 (-2250 3600);
DOT 1 (-2250 3700);
DOT 1 (-2250 3750);
DOT 1 (-2250 3850);
DOT 1 (-2250 3900);
DOT 1 (-2250 3950);
DOT 1 (-2250 4050);
DOT 1 (-650 2250);
DOT 1 (-650 2300);
DOT 1 (-650 2400);
DOT 1 (-650 2350);
DOT 1 (-650 2500);
DOT 1 (-650 2550);
DOT 1 (-650 2650);
DOT 1 (-650 2600);
DOT 1 (-650 2700);
DOT 1 (-650 2750);
DOT 1 (-650 2800);
DOT 1 (-650 2900);
DOT 1 (-650 2850);
DOT 1 (-650 2950);
DOT 1 (-650 3000);
DOT 1 (-650 3050);
DOT 1 (-650 3150);
DOT 1 (-650 3200);
DOT 1 (-650 3100);
DOT 1 (-650 3300);
DOT 1 (-650 3250);
DOT 1 (-650 3350);
DOT 1 (-650 3400);
DOT 1 (-650 3450);
DOT 1 (-650 3500);
DOT 1 (-650 3550);
DOT 1 (-650 3600);
DOT 1 (-650 3650);
DOT 1 (-650 3700);
DOT 1 (-650 3800);
DOT 1 (-650 3750);
DOT 1 (-650 3850);
DOT 1 (-650 3900);
DOT 1 (-650 3950);
DOT 1 (-650 4050);
DOT 1 (-650 4000);
DOT 1 (-2250 4100);
DOT 1 (-2250 4150);
DOT 1 (-2250 4200);
DOT 1 (-2250 4250);
DOT 1 (-2250 4900);
DOT 1 (-2250 5000);
DOT 1 (-2250 5100);
DOT 1 (-650 4150);
DOT 1 (-650 4250);
DOT 1 (-650 4300);
DOT 1 (-650 4350);
DOT 1 (-650 4450);
DOT 1 (-650 4400);
DOT 1 (-650 4500);
DOT 1 (-650 4600);
DOT 1 (-650 4650);
DOT 1 (-650 4800);
DOT 1 (-650 4750);
DOT 1 (-650 4850);
DOT 1 (-650 4900);
DOT 1 (-650 5000);
DOT 1 (-650 5100);
DOT 1 (-650 5200);
DOT 1 (-650 5150);
DOT 1 (-650 5250);
DOT 1 (-650 5300);
DOT 1 (-650 2450);
DOT 1 (-650 4950);
DOT 1 (-650 5050);
DOT 1 (-2250 4800);
DOT 1 (-2250 2850);
DOT 1 (-2250 3650);
DOT 1 (-2250 5150);
DOT 1 (-2250 4000);
DOT 1 (-2250 5300);
DOT 1 (-2250 5350);
DOT 1 (-8875 3400);
DOT 1 (-650 2200);
DOT 1 (-650 2100);
DOT 1 (-650 2000);
DOT 1 (-650 2050);
DOT 1 (-2950 5825);
DOT 1 (-2950 6250);
DOT 1 (-2375 6250);
DOT 1 (-8700 2250);
QUIT
